FILE_TYPE = MACRO_DRAWING;
SET COLOR_WIRE YELLOW;
SET COLOR_PROP MONO;
SET COLOR_DOT WHITE;
SET COLOR_ARC YELLOW;
SET COLOR_BODY GREEN;
SET COLOR_NOTE MONO;
SET PROP_DISPLAY VALUE;
SET PAGE_NUMBER P25;
FORCEADD OFFPAGE..5
(-6425 550);
FORCEPROP 2 LAST $XR1 48 
J 0
(-6769 550);
DISPLAY 0.638298 (-6769 550);
PAINT MONO (-6769 550);
FORCEPROP 2 LAST $XR0 47 
J 0
(-6679 550);
DISPLAY 0.638298 (-6679 550);
PAINT MONO (-6679 550);
FORCEPROP 1 LAST COMMENT_BODY TRUE
J 0
(-6325 475);
DISPLAY 1.170213 (-6325 475);
PAINT GREEN (-6325 475);
DISPLAY INVISIBLE (-6325 475);
FORCEPROP 1 LAST OFFPAGE TRUE
J 0
(-6100 425);
DISPLAY 1.170213 (-6100 425);
PAINT GREEN (-6100 425);
DISPLAY INVISIBLE (-6100 425);
FORCEPROP 2 LAST CDS_LIB mstr_standard
J 0
(-6425 550);
PAINT MONO (-6425 550);
DISPLAY INVISIBLE (-6425 550);
FORCEPROP 2 LAST PATH I1
J 0
(-6375 625);
DISPLAY 1.021277 (-6375 625);
PAINT ORANGE (-6375 625);
DISPLAY INVISIBLE (-6375 625);
FORCEADD TAP..6
(-5575 900);
FORCEPROP 3 LASTPIN (-5525 900) SIG_NAME M_C_CLK_DP<1>
J 0
(-5515 910);
DISPLAY 0.659574 (-5515 910);
PAINT MONO (-5515 910);
DISPLAY INVISIBLE (-5515 910);
FORCEPROP 1 LASTPIN (-5525 900) BN 1
J 0
(-5577 908);
DISPLAY 0.617021 (-5577 908);
PAINT PINK (-5577 908);
FORCEPROP 1 LAST HDL_TAP TRUE
J 0
(-5250 775);
DISPLAY 1.595745 (-5250 775);
PAINT GREEN (-5250 775);
DISPLAY INVISIBLE (-5250 775);
FORCEPROP 1 LAST BODY_TYPE PLUMBING
J 0
(-5575 850);
DISPLAY 1.595745 (-5575 850);
PAINT GREEN (-5575 850);
DISPLAY INVISIBLE (-5575 850);
FORCEPROP 2 LAST CDS_LIB mstr_standard
J 0
(-5575 900);
PAINT MONO (-5575 900);
DISPLAY INVISIBLE (-5575 900);
FORCEPROP 1 LAST PATH I10
J 0
(-5577 900);
DISPLAY 0.872340 (-5577 900);
PAINT GREEN (-5577 900);
DISPLAY INVISIBLE (-5577 900);
FORCEADD TAP..6
R 2
(-2850 1500);
FORCEPROP 3 LASTPIN (-2900 1500) SIG_NAME M_C_ODT<1>
J 0
(-2890 1510);
DISPLAY 0.659574 (-2890 1510);
PAINT MONO (-2890 1510);
DISPLAY INVISIBLE (-2890 1510);
FORCEPROP 1 LASTPIN (-2900 1500) BN 1
J 2
(-2848 1508);
DISPLAY 0.617021 (-2848 1508);
PAINT PINK (-2848 1508);
FORCEPROP 1 LAST HDL_TAP TRUE
J 2
(-3175 1375);
DISPLAY 1.595745 (-3175 1375);
PAINT GREEN (-3175 1375);
DISPLAY INVISIBLE (-3175 1375);
FORCEPROP 1 LAST BODY_TYPE PLUMBING
J 2
(-2850 1450);
DISPLAY 1.595745 (-2850 1450);
PAINT GREEN (-2850 1450);
DISPLAY INVISIBLE (-2850 1450);
FORCEPROP 2 LAST CDS_LIB mstr_standard
J 0
(-2850 1500);
PAINT MONO (-2850 1500);
DISPLAY INVISIBLE (-2850 1500);
FORCEPROP 1 LAST PATH I100
J 2
(-2848 1500);
DISPLAY 0.872340 (-2848 1500);
PAINT GREEN (-2848 1500);
DISPLAY INVISIBLE (-2848 1500);
FORCEADD TAP..6
R 2
(-2850 1550);
FORCEPROP 3 LASTPIN (-2900 1550) SIG_NAME M_C_ODT<2>
J 0
(-2890 1560);
DISPLAY 0.659574 (-2890 1560);
PAINT MONO (-2890 1560);
DISPLAY INVISIBLE (-2890 1560);
FORCEPROP 1 LASTPIN (-2900 1550) BN 2
J 2
(-2848 1558);
DISPLAY 0.617021 (-2848 1558);
PAINT PINK (-2848 1558);
FORCEPROP 1 LAST HDL_TAP TRUE
J 2
(-3175 1425);
DISPLAY 1.595745 (-3175 1425);
PAINT GREEN (-3175 1425);
DISPLAY INVISIBLE (-3175 1425);
FORCEPROP 1 LAST BODY_TYPE PLUMBING
J 2
(-2850 1500);
DISPLAY 1.595745 (-2850 1500);
PAINT GREEN (-2850 1500);
DISPLAY INVISIBLE (-2850 1500);
FORCEPROP 2 LAST CDS_LIB mstr_standard
J 0
(-2850 1550);
PAINT MONO (-2850 1550);
DISPLAY INVISIBLE (-2850 1550);
FORCEPROP 1 LAST PATH I101
J 2
(-2848 1550);
DISPLAY 0.872340 (-2848 1550);
PAINT GREEN (-2848 1550);
DISPLAY INVISIBLE (-2848 1550);
FORCEADD TAP..6
R 2
(-2850 1600);
FORCEPROP 3 LASTPIN (-2900 1600) SIG_NAME M_C_ODT<3>
J 0
(-2890 1610);
DISPLAY 0.659574 (-2890 1610);
PAINT MONO (-2890 1610);
DISPLAY INVISIBLE (-2890 1610);
FORCEPROP 1 LASTPIN (-2900 1600) BN 3
J 2
(-2848 1608);
DISPLAY 0.617021 (-2848 1608);
PAINT PINK (-2848 1608);
FORCEPROP 1 LAST HDL_TAP TRUE
J 2
(-3175 1475);
DISPLAY 1.595745 (-3175 1475);
PAINT GREEN (-3175 1475);
DISPLAY INVISIBLE (-3175 1475);
FORCEPROP 1 LAST BODY_TYPE PLUMBING
J 2
(-2850 1550);
DISPLAY 1.595745 (-2850 1550);
PAINT GREEN (-2850 1550);
DISPLAY INVISIBLE (-2850 1550);
FORCEPROP 2 LAST CDS_LIB mstr_standard
J 0
(-2850 1600);
PAINT MONO (-2850 1600);
DISPLAY INVISIBLE (-2850 1600);
FORCEPROP 1 LAST PATH I102
J 2
(-2848 1600);
DISPLAY 0.872340 (-2848 1600);
PAINT GREEN (-2848 1600);
DISPLAY INVISIBLE (-2848 1600);
FORCEADD TAP..6
R 2
(-2850 1700);
FORCEPROP 3 LASTPIN (-2900 1700) SIG_NAME M_C_CKE<0>
J 0
(-2890 1710);
DISPLAY 0.659574 (-2890 1710);
PAINT MONO (-2890 1710);
DISPLAY INVISIBLE (-2890 1710);
FORCEPROP 1 LASTPIN (-2900 1700) BN 0
J 2
(-2848 1708);
DISPLAY 0.617021 (-2848 1708);
PAINT PINK (-2848 1708);
FORCEPROP 1 LAST HDL_TAP TRUE
J 2
(-3175 1575);
DISPLAY 1.595745 (-3175 1575);
PAINT GREEN (-3175 1575);
DISPLAY INVISIBLE (-3175 1575);
FORCEPROP 1 LAST BODY_TYPE PLUMBING
J 2
(-2850 1650);
DISPLAY 1.595745 (-2850 1650);
PAINT GREEN (-2850 1650);
DISPLAY INVISIBLE (-2850 1650);
FORCEPROP 2 LAST CDS_LIB mstr_standard
J 0
(-2850 1700);
PAINT MONO (-2850 1700);
DISPLAY INVISIBLE (-2850 1700);
FORCEPROP 1 LAST PATH I103
J 2
(-2848 1700);
DISPLAY 0.872340 (-2848 1700);
PAINT GREEN (-2848 1700);
DISPLAY INVISIBLE (-2848 1700);
FORCEADD TAP..6
R 2
(-2850 1750);
FORCEPROP 3 LASTPIN (-2900 1750) SIG_NAME M_C_CKE<1>
J 0
(-2890 1760);
DISPLAY 0.659574 (-2890 1760);
PAINT MONO (-2890 1760);
DISPLAY INVISIBLE (-2890 1760);
FORCEPROP 1 LASTPIN (-2900 1750) BN 1
J 2
(-2848 1758);
DISPLAY 0.617021 (-2848 1758);
PAINT PINK (-2848 1758);
FORCEPROP 1 LAST HDL_TAP TRUE
J 2
(-3175 1625);
DISPLAY 1.595745 (-3175 1625);
PAINT GREEN (-3175 1625);
DISPLAY INVISIBLE (-3175 1625);
FORCEPROP 1 LAST BODY_TYPE PLUMBING
J 2
(-2850 1700);
DISPLAY 1.595745 (-2850 1700);
PAINT GREEN (-2850 1700);
DISPLAY INVISIBLE (-2850 1700);
FORCEPROP 2 LAST CDS_LIB mstr_standard
J 0
(-2850 1750);
PAINT MONO (-2850 1750);
DISPLAY INVISIBLE (-2850 1750);
FORCEPROP 1 LAST PATH I104
J 2
(-2848 1750);
DISPLAY 0.872340 (-2848 1750);
PAINT GREEN (-2848 1750);
DISPLAY INVISIBLE (-2848 1750);
FORCEADD TAP..6
R 2
(-2850 1800);
FORCEPROP 3 LASTPIN (-2900 1800) SIG_NAME M_C_CKE<2>
J 0
(-2890 1810);
DISPLAY 0.659574 (-2890 1810);
PAINT MONO (-2890 1810);
DISPLAY INVISIBLE (-2890 1810);
FORCEPROP 1 LASTPIN (-2900 1800) BN 2
J 2
(-2848 1808);
DISPLAY 0.617021 (-2848 1808);
PAINT PINK (-2848 1808);
FORCEPROP 1 LAST HDL_TAP TRUE
J 2
(-3175 1675);
DISPLAY 1.595745 (-3175 1675);
PAINT GREEN (-3175 1675);
DISPLAY INVISIBLE (-3175 1675);
FORCEPROP 1 LAST BODY_TYPE PLUMBING
J 2
(-2850 1750);
DISPLAY 1.595745 (-2850 1750);
PAINT GREEN (-2850 1750);
DISPLAY INVISIBLE (-2850 1750);
FORCEPROP 2 LAST CDS_LIB mstr_standard
J 0
(-2850 1800);
PAINT MONO (-2850 1800);
DISPLAY INVISIBLE (-2850 1800);
FORCEPROP 1 LAST PATH I105
J 2
(-2848 1800);
DISPLAY 0.872340 (-2848 1800);
PAINT GREEN (-2848 1800);
DISPLAY INVISIBLE (-2848 1800);
FORCEADD TAP..6
R 2
(-2850 1850);
FORCEPROP 3 LASTPIN (-2900 1850) SIG_NAME M_C_CKE<3>
J 0
(-2890 1860);
DISPLAY 0.659574 (-2890 1860);
PAINT MONO (-2890 1860);
DISPLAY INVISIBLE (-2890 1860);
FORCEPROP 1 LASTPIN (-2900 1850) BN 3
J 2
(-2848 1858);
DISPLAY 0.617021 (-2848 1858);
PAINT PINK (-2848 1858);
FORCEPROP 1 LAST HDL_TAP TRUE
J 2
(-3175 1725);
DISPLAY 1.595745 (-3175 1725);
PAINT GREEN (-3175 1725);
DISPLAY INVISIBLE (-3175 1725);
FORCEPROP 1 LAST BODY_TYPE PLUMBING
J 2
(-2850 1800);
DISPLAY 1.595745 (-2850 1800);
PAINT GREEN (-2850 1800);
DISPLAY INVISIBLE (-2850 1800);
FORCEPROP 2 LAST CDS_LIB mstr_standard
J 0
(-2850 1850);
PAINT MONO (-2850 1850);
DISPLAY INVISIBLE (-2850 1850);
FORCEPROP 1 LAST PATH I106
J 2
(-2848 1850);
DISPLAY 0.872340 (-2848 1850);
PAINT GREEN (-2848 1850);
DISPLAY INVISIBLE (-2848 1850);
FORCEADD TAP..6
R 2
(-2850 1950);
FORCEPROP 3 LASTPIN (-2900 1950) SIG_NAME M_C_MA<0>
J 0
(-2890 1960);
DISPLAY 0.659574 (-2890 1960);
PAINT MONO (-2890 1960);
DISPLAY INVISIBLE (-2890 1960);
FORCEPROP 1 LASTPIN (-2900 1950) BN 0
J 2
(-2848 1958);
DISPLAY 0.617021 (-2848 1958);
PAINT PINK (-2848 1958);
FORCEPROP 1 LAST HDL_TAP TRUE
J 2
(-3175 1825);
DISPLAY 1.595745 (-3175 1825);
PAINT GREEN (-3175 1825);
DISPLAY INVISIBLE (-3175 1825);
FORCEPROP 1 LAST BODY_TYPE PLUMBING
J 2
(-2850 1900);
DISPLAY 1.595745 (-2850 1900);
PAINT GREEN (-2850 1900);
DISPLAY INVISIBLE (-2850 1900);
FORCEPROP 2 LAST CDS_LIB mstr_standard
J 0
(-2850 1950);
PAINT MONO (-2850 1950);
DISPLAY INVISIBLE (-2850 1950);
FORCEPROP 1 LAST PATH I107
J 2
(-2848 1950);
DISPLAY 0.872340 (-2848 1950);
PAINT GREEN (-2848 1950);
DISPLAY INVISIBLE (-2848 1950);
FORCEADD TAP..6
R 2
(-2850 2050);
FORCEPROP 3 LASTPIN (-2900 2050) SIG_NAME M_C_MA<2>
J 0
(-2890 2060);
DISPLAY 0.659574 (-2890 2060);
PAINT MONO (-2890 2060);
DISPLAY INVISIBLE (-2890 2060);
FORCEPROP 1 LASTPIN (-2900 2050) BN 2
J 2
(-2848 2058);
DISPLAY 0.617021 (-2848 2058);
PAINT PINK (-2848 2058);
FORCEPROP 1 LAST HDL_TAP TRUE
J 2
(-3175 1925);
DISPLAY 1.595745 (-3175 1925);
PAINT GREEN (-3175 1925);
DISPLAY INVISIBLE (-3175 1925);
FORCEPROP 1 LAST BODY_TYPE PLUMBING
J 2
(-2850 2000);
DISPLAY 1.595745 (-2850 2000);
PAINT GREEN (-2850 2000);
DISPLAY INVISIBLE (-2850 2000);
FORCEPROP 2 LAST CDS_LIB mstr_standard
J 0
(-2850 2050);
PAINT MONO (-2850 2050);
DISPLAY INVISIBLE (-2850 2050);
FORCEPROP 1 LAST PATH I108
J 2
(-2848 2050);
DISPLAY 0.872340 (-2848 2050);
PAINT GREEN (-2848 2050);
DISPLAY INVISIBLE (-2848 2050);
FORCEADD TAP..6
R 2
(-2850 2000);
FORCEPROP 3 LASTPIN (-2900 2000) SIG_NAME M_C_MA<1>
J 0
(-2890 2010);
DISPLAY 0.659574 (-2890 2010);
PAINT MONO (-2890 2010);
DISPLAY INVISIBLE (-2890 2010);
FORCEPROP 1 LASTPIN (-2900 2000) BN 1
J 2
(-2848 2008);
DISPLAY 0.617021 (-2848 2008);
PAINT PINK (-2848 2008);
FORCEPROP 1 LAST HDL_TAP TRUE
J 2
(-3175 1875);
DISPLAY 1.595745 (-3175 1875);
PAINT GREEN (-3175 1875);
DISPLAY INVISIBLE (-3175 1875);
FORCEPROP 1 LAST BODY_TYPE PLUMBING
J 2
(-2850 1950);
DISPLAY 1.595745 (-2850 1950);
PAINT GREEN (-2850 1950);
DISPLAY INVISIBLE (-2850 1950);
FORCEPROP 2 LAST CDS_LIB mstr_standard
J 0
(-2850 2000);
PAINT MONO (-2850 2000);
DISPLAY INVISIBLE (-2850 2000);
FORCEPROP 1 LAST PATH I109
J 2
(-2848 2000);
DISPLAY 0.872340 (-2848 2000);
PAINT GREEN (-2848 2000);
DISPLAY INVISIBLE (-2848 2000);
FORCEADD TAP..6
(-5575 950);
FORCEPROP 3 LASTPIN (-5525 950) SIG_NAME M_C_CLK_DP<2>
J 0
(-5515 960);
DISPLAY 0.659574 (-5515 960);
PAINT MONO (-5515 960);
DISPLAY INVISIBLE (-5515 960);
FORCEPROP 1 LASTPIN (-5525 950) BN 2
J 0
(-5577 958);
DISPLAY 0.617021 (-5577 958);
PAINT PINK (-5577 958);
FORCEPROP 1 LAST HDL_TAP TRUE
J 0
(-5250 825);
DISPLAY 1.595745 (-5250 825);
PAINT GREEN (-5250 825);
DISPLAY INVISIBLE (-5250 825);
FORCEPROP 1 LAST BODY_TYPE PLUMBING
J 0
(-5575 900);
DISPLAY 1.595745 (-5575 900);
PAINT GREEN (-5575 900);
DISPLAY INVISIBLE (-5575 900);
FORCEPROP 2 LAST CDS_LIB mstr_standard
J 0
(-5575 950);
PAINT MONO (-5575 950);
DISPLAY INVISIBLE (-5575 950);
FORCEPROP 1 LAST PATH I11
J 0
(-5577 950);
DISPLAY 0.872340 (-5577 950);
PAINT GREEN (-5577 950);
DISPLAY INVISIBLE (-5577 950);
FORCEADD TAP..6
R 2
(-2850 2100);
FORCEPROP 3 LASTPIN (-2900 2100) SIG_NAME M_C_MA<3>
J 0
(-2890 2110);
DISPLAY 0.659574 (-2890 2110);
PAINT MONO (-2890 2110);
DISPLAY INVISIBLE (-2890 2110);
FORCEPROP 1 LASTPIN (-2900 2100) BN 3
J 2
(-2848 2108);
DISPLAY 0.617021 (-2848 2108);
PAINT PINK (-2848 2108);
FORCEPROP 1 LAST HDL_TAP TRUE
J 2
(-3175 1975);
DISPLAY 1.595745 (-3175 1975);
PAINT GREEN (-3175 1975);
DISPLAY INVISIBLE (-3175 1975);
FORCEPROP 1 LAST BODY_TYPE PLUMBING
J 2
(-2850 2050);
DISPLAY 1.595745 (-2850 2050);
PAINT GREEN (-2850 2050);
DISPLAY INVISIBLE (-2850 2050);
FORCEPROP 2 LAST CDS_LIB mstr_standard
J 0
(-2850 2100);
PAINT MONO (-2850 2100);
DISPLAY INVISIBLE (-2850 2100);
FORCEPROP 1 LAST PATH I110
J 2
(-2848 2100);
DISPLAY 0.872340 (-2848 2100);
PAINT GREEN (-2848 2100);
DISPLAY INVISIBLE (-2848 2100);
FORCEADD TAP..6
R 2
(-2850 2150);
FORCEPROP 3 LASTPIN (-2900 2150) SIG_NAME M_C_MA<4>
J 0
(-2890 2160);
DISPLAY 0.659574 (-2890 2160);
PAINT MONO (-2890 2160);
DISPLAY INVISIBLE (-2890 2160);
FORCEPROP 1 LASTPIN (-2900 2150) BN 4
J 2
(-2848 2158);
DISPLAY 0.617021 (-2848 2158);
PAINT PINK (-2848 2158);
FORCEPROP 1 LAST HDL_TAP TRUE
J 2
(-3175 2025);
DISPLAY 1.595745 (-3175 2025);
PAINT GREEN (-3175 2025);
DISPLAY INVISIBLE (-3175 2025);
FORCEPROP 1 LAST BODY_TYPE PLUMBING
J 2
(-2850 2100);
DISPLAY 1.595745 (-2850 2100);
PAINT GREEN (-2850 2100);
DISPLAY INVISIBLE (-2850 2100);
FORCEPROP 2 LAST CDS_LIB mstr_standard
J 0
(-2850 2150);
PAINT MONO (-2850 2150);
DISPLAY INVISIBLE (-2850 2150);
FORCEPROP 1 LAST PATH I111
J 2
(-2848 2150);
DISPLAY 0.872340 (-2848 2150);
PAINT GREEN (-2848 2150);
DISPLAY INVISIBLE (-2848 2150);
FORCEADD TAP..6
R 2
(-2850 2200);
FORCEPROP 3 LASTPIN (-2900 2200) SIG_NAME M_C_MA<5>
J 0
(-2890 2210);
DISPLAY 0.659574 (-2890 2210);
PAINT MONO (-2890 2210);
DISPLAY INVISIBLE (-2890 2210);
FORCEPROP 1 LASTPIN (-2900 2200) BN 5
J 2
(-2848 2208);
DISPLAY 0.617021 (-2848 2208);
PAINT PINK (-2848 2208);
FORCEPROP 1 LAST HDL_TAP TRUE
J 2
(-3175 2075);
DISPLAY 1.595745 (-3175 2075);
PAINT GREEN (-3175 2075);
DISPLAY INVISIBLE (-3175 2075);
FORCEPROP 1 LAST BODY_TYPE PLUMBING
J 2
(-2850 2150);
DISPLAY 1.595745 (-2850 2150);
PAINT GREEN (-2850 2150);
DISPLAY INVISIBLE (-2850 2150);
FORCEPROP 2 LAST CDS_LIB mstr_standard
J 0
(-2850 2200);
PAINT MONO (-2850 2200);
DISPLAY INVISIBLE (-2850 2200);
FORCEPROP 1 LAST PATH I112
J 2
(-2848 2200);
DISPLAY 0.872340 (-2848 2200);
PAINT GREEN (-2848 2200);
DISPLAY INVISIBLE (-2848 2200);
FORCEADD TAP..6
R 2
(-2850 2250);
FORCEPROP 3 LASTPIN (-2900 2250) SIG_NAME M_C_MA<6>
J 0
(-2890 2260);
DISPLAY 0.659574 (-2890 2260);
PAINT MONO (-2890 2260);
DISPLAY INVISIBLE (-2890 2260);
FORCEPROP 1 LASTPIN (-2900 2250) BN 6
J 2
(-2848 2258);
DISPLAY 0.617021 (-2848 2258);
PAINT PINK (-2848 2258);
FORCEPROP 1 LAST HDL_TAP TRUE
J 2
(-3175 2125);
DISPLAY 1.595745 (-3175 2125);
PAINT GREEN (-3175 2125);
DISPLAY INVISIBLE (-3175 2125);
FORCEPROP 1 LAST BODY_TYPE PLUMBING
J 2
(-2850 2200);
DISPLAY 1.595745 (-2850 2200);
PAINT GREEN (-2850 2200);
DISPLAY INVISIBLE (-2850 2200);
FORCEPROP 2 LAST CDS_LIB mstr_standard
J 0
(-2850 2250);
PAINT MONO (-2850 2250);
DISPLAY INVISIBLE (-2850 2250);
FORCEPROP 1 LAST PATH I113
J 2
(-2848 2250);
DISPLAY 0.872340 (-2848 2250);
PAINT GREEN (-2848 2250);
DISPLAY INVISIBLE (-2848 2250);
FORCEADD TAP..6
R 2
(-2850 2300);
FORCEPROP 3 LASTPIN (-2900 2300) SIG_NAME M_C_MA<7>
J 0
(-2890 2310);
DISPLAY 0.659574 (-2890 2310);
PAINT MONO (-2890 2310);
DISPLAY INVISIBLE (-2890 2310);
FORCEPROP 1 LASTPIN (-2900 2300) BN 7
J 2
(-2848 2308);
DISPLAY 0.617021 (-2848 2308);
PAINT PINK (-2848 2308);
FORCEPROP 1 LAST HDL_TAP TRUE
J 2
(-3175 2175);
DISPLAY 1.595745 (-3175 2175);
PAINT GREEN (-3175 2175);
DISPLAY INVISIBLE (-3175 2175);
FORCEPROP 1 LAST BODY_TYPE PLUMBING
J 2
(-2850 2250);
DISPLAY 1.595745 (-2850 2250);
PAINT GREEN (-2850 2250);
DISPLAY INVISIBLE (-2850 2250);
FORCEPROP 2 LAST CDS_LIB mstr_standard
J 0
(-2850 2300);
PAINT MONO (-2850 2300);
DISPLAY INVISIBLE (-2850 2300);
FORCEPROP 1 LAST PATH I114
J 2
(-2848 2300);
DISPLAY 0.872340 (-2848 2300);
PAINT GREEN (-2848 2300);
DISPLAY INVISIBLE (-2848 2300);
FORCEADD TAP..6
R 2
(-2850 2350);
FORCEPROP 3 LASTPIN (-2900 2350) SIG_NAME M_C_MA<8>
J 0
(-2890 2360);
DISPLAY 0.659574 (-2890 2360);
PAINT MONO (-2890 2360);
DISPLAY INVISIBLE (-2890 2360);
FORCEPROP 1 LASTPIN (-2900 2350) BN 8
J 2
(-2848 2358);
DISPLAY 0.617021 (-2848 2358);
PAINT PINK (-2848 2358);
FORCEPROP 1 LAST HDL_TAP TRUE
J 2
(-3175 2225);
DISPLAY 1.595745 (-3175 2225);
PAINT GREEN (-3175 2225);
DISPLAY INVISIBLE (-3175 2225);
FORCEPROP 1 LAST BODY_TYPE PLUMBING
J 2
(-2850 2300);
DISPLAY 1.595745 (-2850 2300);
PAINT GREEN (-2850 2300);
DISPLAY INVISIBLE (-2850 2300);
FORCEPROP 2 LAST CDS_LIB mstr_standard
J 0
(-2850 2350);
PAINT MONO (-2850 2350);
DISPLAY INVISIBLE (-2850 2350);
FORCEPROP 1 LAST PATH I115
J 2
(-2848 2350);
DISPLAY 0.872340 (-2848 2350);
PAINT GREEN (-2848 2350);
DISPLAY INVISIBLE (-2848 2350);
FORCEADD TAP..6
R 2
(-2850 2400);
FORCEPROP 3 LASTPIN (-2900 2400) SIG_NAME M_C_MA<9>
J 0
(-2890 2410);
DISPLAY 0.659574 (-2890 2410);
PAINT MONO (-2890 2410);
DISPLAY INVISIBLE (-2890 2410);
FORCEPROP 1 LASTPIN (-2900 2400) BN 9
J 2
(-2848 2408);
DISPLAY 0.617021 (-2848 2408);
PAINT PINK (-2848 2408);
FORCEPROP 1 LAST HDL_TAP TRUE
J 2
(-3175 2275);
DISPLAY 1.595745 (-3175 2275);
PAINT GREEN (-3175 2275);
DISPLAY INVISIBLE (-3175 2275);
FORCEPROP 1 LAST BODY_TYPE PLUMBING
J 2
(-2850 2350);
DISPLAY 1.595745 (-2850 2350);
PAINT GREEN (-2850 2350);
DISPLAY INVISIBLE (-2850 2350);
FORCEPROP 2 LAST CDS_LIB mstr_standard
J 0
(-2850 2400);
PAINT MONO (-2850 2400);
DISPLAY INVISIBLE (-2850 2400);
FORCEPROP 1 LAST PATH I116
J 2
(-2848 2400);
DISPLAY 0.872340 (-2848 2400);
PAINT GREEN (-2848 2400);
DISPLAY INVISIBLE (-2848 2400);
FORCEADD TAP..6
R 2
(-2850 2450);
FORCEPROP 3 LASTPIN (-2900 2450) SIG_NAME M_C_MA<10>
J 0
(-2890 2460);
DISPLAY 0.659574 (-2890 2460);
PAINT MONO (-2890 2460);
DISPLAY INVISIBLE (-2890 2460);
FORCEPROP 1 LASTPIN (-2900 2450) BN 10
J 2
(-2848 2458);
DISPLAY 0.617021 (-2848 2458);
PAINT PINK (-2848 2458);
FORCEPROP 1 LAST HDL_TAP TRUE
J 2
(-3175 2325);
DISPLAY 1.595745 (-3175 2325);
PAINT GREEN (-3175 2325);
DISPLAY INVISIBLE (-3175 2325);
FORCEPROP 1 LAST BODY_TYPE PLUMBING
J 2
(-2850 2400);
DISPLAY 1.595745 (-2850 2400);
PAINT GREEN (-2850 2400);
DISPLAY INVISIBLE (-2850 2400);
FORCEPROP 2 LAST CDS_LIB mstr_standard
J 0
(-2850 2450);
PAINT MONO (-2850 2450);
DISPLAY INVISIBLE (-2850 2450);
FORCEPROP 1 LAST PATH I117
J 2
(-2848 2450);
DISPLAY 0.872340 (-2848 2450);
PAINT GREEN (-2848 2450);
DISPLAY INVISIBLE (-2848 2450);
FORCEADD TAP..6
R 2
(-2850 2500);
FORCEPROP 3 LASTPIN (-2900 2500) SIG_NAME M_C_MA<11>
J 0
(-2890 2510);
DISPLAY 0.659574 (-2890 2510);
PAINT MONO (-2890 2510);
DISPLAY INVISIBLE (-2890 2510);
FORCEPROP 1 LASTPIN (-2900 2500) BN 11
J 2
(-2848 2508);
DISPLAY 0.617021 (-2848 2508);
PAINT PINK (-2848 2508);
FORCEPROP 1 LAST HDL_TAP TRUE
J 2
(-3175 2375);
DISPLAY 1.595745 (-3175 2375);
PAINT GREEN (-3175 2375);
DISPLAY INVISIBLE (-3175 2375);
FORCEPROP 1 LAST BODY_TYPE PLUMBING
J 2
(-2850 2450);
DISPLAY 1.595745 (-2850 2450);
PAINT GREEN (-2850 2450);
DISPLAY INVISIBLE (-2850 2450);
FORCEPROP 2 LAST CDS_LIB mstr_standard
J 0
(-2850 2500);
PAINT MONO (-2850 2500);
DISPLAY INVISIBLE (-2850 2500);
FORCEPROP 1 LAST PATH I118
J 2
(-2848 2500);
DISPLAY 0.872340 (-2848 2500);
PAINT GREEN (-2848 2500);
DISPLAY INVISIBLE (-2848 2500);
FORCEADD TAP..6
R 2
(-2850 2550);
FORCEPROP 3 LASTPIN (-2900 2550) SIG_NAME M_C_MA<12>
J 0
(-2890 2560);
DISPLAY 0.659574 (-2890 2560);
PAINT MONO (-2890 2560);
DISPLAY INVISIBLE (-2890 2560);
FORCEPROP 1 LASTPIN (-2900 2550) BN 12
J 2
(-2848 2558);
DISPLAY 0.617021 (-2848 2558);
PAINT PINK (-2848 2558);
FORCEPROP 1 LAST HDL_TAP TRUE
J 2
(-3175 2425);
DISPLAY 1.595745 (-3175 2425);
PAINT GREEN (-3175 2425);
DISPLAY INVISIBLE (-3175 2425);
FORCEPROP 1 LAST BODY_TYPE PLUMBING
J 2
(-2850 2500);
DISPLAY 1.595745 (-2850 2500);
PAINT GREEN (-2850 2500);
DISPLAY INVISIBLE (-2850 2500);
FORCEPROP 2 LAST CDS_LIB mstr_standard
J 0
(-2850 2550);
PAINT MONO (-2850 2550);
DISPLAY INVISIBLE (-2850 2550);
FORCEPROP 1 LAST PATH I119
J 2
(-2848 2550);
DISPLAY 0.872340 (-2848 2550);
PAINT GREEN (-2848 2550);
DISPLAY INVISIBLE (-2848 2550);
FORCEADD TAP..6
(-5575 1000);
FORCEPROP 3 LASTPIN (-5525 1000) SIG_NAME M_C_CLK_DP<3>
J 0
(-5515 1010);
DISPLAY 0.659574 (-5515 1010);
PAINT MONO (-5515 1010);
DISPLAY INVISIBLE (-5515 1010);
FORCEPROP 1 LASTPIN (-5525 1000) BN 3
J 0
(-5577 1008);
DISPLAY 0.617021 (-5577 1008);
PAINT PINK (-5577 1008);
FORCEPROP 1 LAST HDL_TAP TRUE
J 0
(-5250 875);
DISPLAY 1.595745 (-5250 875);
PAINT GREEN (-5250 875);
DISPLAY INVISIBLE (-5250 875);
FORCEPROP 1 LAST BODY_TYPE PLUMBING
J 0
(-5575 950);
DISPLAY 1.595745 (-5575 950);
PAINT GREEN (-5575 950);
DISPLAY INVISIBLE (-5575 950);
FORCEPROP 2 LAST CDS_LIB mstr_standard
J 0
(-5575 1000);
PAINT MONO (-5575 1000);
DISPLAY INVISIBLE (-5575 1000);
FORCEPROP 1 LAST PATH I12
J 0
(-5577 1000);
DISPLAY 0.872340 (-5577 1000);
PAINT GREEN (-5577 1000);
DISPLAY INVISIBLE (-5577 1000);
FORCEADD TAP..6
R 2
(-2850 2600);
FORCEPROP 3 LASTPIN (-2900 2600) SIG_NAME M_C_MA<13>
J 0
(-2890 2610);
DISPLAY 0.659574 (-2890 2610);
PAINT MONO (-2890 2610);
DISPLAY INVISIBLE (-2890 2610);
FORCEPROP 1 LASTPIN (-2900 2600) BN 13
J 2
(-2848 2608);
DISPLAY 0.617021 (-2848 2608);
PAINT PINK (-2848 2608);
FORCEPROP 1 LAST HDL_TAP TRUE
J 2
(-3175 2475);
DISPLAY 1.595745 (-3175 2475);
PAINT GREEN (-3175 2475);
DISPLAY INVISIBLE (-3175 2475);
FORCEPROP 1 LAST BODY_TYPE PLUMBING
J 2
(-2850 2550);
DISPLAY 1.595745 (-2850 2550);
PAINT GREEN (-2850 2550);
DISPLAY INVISIBLE (-2850 2550);
FORCEPROP 2 LAST CDS_LIB mstr_standard
J 0
(-2850 2600);
PAINT MONO (-2850 2600);
DISPLAY INVISIBLE (-2850 2600);
FORCEPROP 1 LAST PATH I120
J 2
(-2848 2600);
DISPLAY 0.872340 (-2848 2600);
PAINT GREEN (-2848 2600);
DISPLAY INVISIBLE (-2848 2600);
FORCEADD TAP..6
R 2
(-2850 2650);
FORCEPROP 3 LASTPIN (-2900 2650) SIG_NAME M_C_MA<14>
J 0
(-2890 2660);
DISPLAY 0.659574 (-2890 2660);
PAINT MONO (-2890 2660);
DISPLAY INVISIBLE (-2890 2660);
FORCEPROP 1 LASTPIN (-2900 2650) BN 14
J 2
(-2848 2658);
DISPLAY 0.617021 (-2848 2658);
PAINT PINK (-2848 2658);
FORCEPROP 1 LAST HDL_TAP TRUE
J 2
(-3175 2525);
DISPLAY 1.595745 (-3175 2525);
PAINT GREEN (-3175 2525);
DISPLAY INVISIBLE (-3175 2525);
FORCEPROP 1 LAST BODY_TYPE PLUMBING
J 2
(-2850 2600);
DISPLAY 1.595745 (-2850 2600);
PAINT GREEN (-2850 2600);
DISPLAY INVISIBLE (-2850 2600);
FORCEPROP 2 LAST CDS_LIB mstr_standard
J 0
(-2850 2650);
PAINT MONO (-2850 2650);
DISPLAY INVISIBLE (-2850 2650);
FORCEPROP 1 LAST PATH I121
J 2
(-2848 2650);
DISPLAY 0.872340 (-2848 2650);
PAINT GREEN (-2848 2650);
DISPLAY INVISIBLE (-2848 2650);
FORCEADD TAP..6
R 2
(-2850 2700);
FORCEPROP 3 LASTPIN (-2900 2700) SIG_NAME M_C_MA<15>
J 0
(-2890 2710);
DISPLAY 0.659574 (-2890 2710);
PAINT MONO (-2890 2710);
DISPLAY INVISIBLE (-2890 2710);
FORCEPROP 1 LASTPIN (-2900 2700) BN 15
J 2
(-2848 2708);
DISPLAY 0.617021 (-2848 2708);
PAINT PINK (-2848 2708);
FORCEPROP 1 LAST HDL_TAP TRUE
J 2
(-3175 2575);
DISPLAY 1.595745 (-3175 2575);
PAINT GREEN (-3175 2575);
DISPLAY INVISIBLE (-3175 2575);
FORCEPROP 1 LAST BODY_TYPE PLUMBING
J 2
(-2850 2650);
DISPLAY 1.595745 (-2850 2650);
PAINT GREEN (-2850 2650);
DISPLAY INVISIBLE (-2850 2650);
FORCEPROP 2 LAST CDS_LIB mstr_standard
J 0
(-2850 2700);
PAINT MONO (-2850 2700);
DISPLAY INVISIBLE (-2850 2700);
FORCEPROP 1 LAST PATH I122
J 2
(-2848 2700);
DISPLAY 0.872340 (-2848 2700);
PAINT GREEN (-2848 2700);
DISPLAY INVISIBLE (-2848 2700);
FORCEADD TAP..6
R 2
(-2850 2750);
FORCEPROP 3 LASTPIN (-2900 2750) SIG_NAME M_C_MA<16>
J 0
(-2890 2760);
DISPLAY 0.659574 (-2890 2760);
PAINT MONO (-2890 2760);
DISPLAY INVISIBLE (-2890 2760);
FORCEPROP 1 LASTPIN (-2900 2750) BN 16
J 2
(-2848 2758);
DISPLAY 0.617021 (-2848 2758);
PAINT PINK (-2848 2758);
FORCEPROP 1 LAST HDL_TAP TRUE
J 2
(-3175 2625);
DISPLAY 1.595745 (-3175 2625);
PAINT GREEN (-3175 2625);
DISPLAY INVISIBLE (-3175 2625);
FORCEPROP 1 LAST BODY_TYPE PLUMBING
J 2
(-2850 2700);
DISPLAY 1.595745 (-2850 2700);
PAINT GREEN (-2850 2700);
DISPLAY INVISIBLE (-2850 2700);
FORCEPROP 2 LAST CDS_LIB mstr_standard
J 0
(-2850 2750);
PAINT MONO (-2850 2750);
DISPLAY INVISIBLE (-2850 2750);
FORCEPROP 1 LAST PATH I123
J 2
(-2848 2750);
DISPLAY 0.872340 (-2848 2750);
PAINT GREEN (-2848 2750);
DISPLAY INVISIBLE (-2848 2750);
FORCEADD TAP..6
R 2
(-2850 2800);
FORCEPROP 3 LASTPIN (-2900 2800) SIG_NAME M_C_MA<17>
J 0
(-2890 2810);
DISPLAY 0.659574 (-2890 2810);
PAINT MONO (-2890 2810);
DISPLAY INVISIBLE (-2890 2810);
FORCEPROP 1 LASTPIN (-2900 2800) BN 17
J 2
(-2848 2808);
DISPLAY 0.617021 (-2848 2808);
PAINT PINK (-2848 2808);
FORCEPROP 1 LAST HDL_TAP TRUE
J 2
(-3175 2675);
DISPLAY 1.595745 (-3175 2675);
PAINT GREEN (-3175 2675);
DISPLAY INVISIBLE (-3175 2675);
FORCEPROP 1 LAST BODY_TYPE PLUMBING
J 2
(-2850 2750);
DISPLAY 1.595745 (-2850 2750);
PAINT GREEN (-2850 2750);
DISPLAY INVISIBLE (-2850 2750);
FORCEPROP 2 LAST CDS_LIB mstr_standard
J 0
(-2850 2800);
PAINT MONO (-2850 2800);
DISPLAY INVISIBLE (-2850 2800);
FORCEPROP 1 LAST PATH I124
J 2
(-2848 2800);
DISPLAY 0.872340 (-2848 2800);
PAINT GREEN (-2848 2800);
DISPLAY INVISIBLE (-2848 2800);
FORCEADD TAP..6
R 2
(-2850 2950);
FORCEPROP 3 LASTPIN (-2900 2950) SIG_NAME M_C_DQS_DN<1>
J 0
(-2890 2960);
DISPLAY 0.659574 (-2890 2960);
PAINT MONO (-2890 2960);
DISPLAY INVISIBLE (-2890 2960);
FORCEPROP 1 LASTPIN (-2900 2950) BN 1
J 2
(-2848 2958);
DISPLAY 0.617021 (-2848 2958);
PAINT PINK (-2848 2958);
FORCEPROP 1 LAST HDL_TAP TRUE
J 2
(-3175 2825);
DISPLAY 1.595745 (-3175 2825);
PAINT GREEN (-3175 2825);
DISPLAY INVISIBLE (-3175 2825);
FORCEPROP 1 LAST BODY_TYPE PLUMBING
J 2
(-2850 2900);
DISPLAY 1.595745 (-2850 2900);
PAINT GREEN (-2850 2900);
DISPLAY INVISIBLE (-2850 2900);
FORCEPROP 2 LAST CDS_LIB mstr_standard
J 0
(-2850 2950);
PAINT MONO (-2850 2950);
DISPLAY INVISIBLE (-2850 2950);
FORCEPROP 1 LAST PATH I125
J 2
(-2848 2950);
DISPLAY 0.872340 (-2848 2950);
PAINT GREEN (-2848 2950);
DISPLAY INVISIBLE (-2848 2950);
FORCEADD TAP..6
R 2
(-2850 2900);
FORCEPROP 3 LASTPIN (-2900 2900) SIG_NAME M_C_DQS_DN<0>
J 0
(-2890 2910);
DISPLAY 0.659574 (-2890 2910);
PAINT MONO (-2890 2910);
DISPLAY INVISIBLE (-2890 2910);
FORCEPROP 1 LASTPIN (-2900 2900) BN 0
J 2
(-2848 2908);
DISPLAY 0.617021 (-2848 2908);
PAINT PINK (-2848 2908);
FORCEPROP 1 LAST HDL_TAP TRUE
J 2
(-3175 2775);
DISPLAY 1.595745 (-3175 2775);
PAINT GREEN (-3175 2775);
DISPLAY INVISIBLE (-3175 2775);
FORCEPROP 1 LAST BODY_TYPE PLUMBING
J 2
(-2850 2850);
DISPLAY 1.595745 (-2850 2850);
PAINT GREEN (-2850 2850);
DISPLAY INVISIBLE (-2850 2850);
FORCEPROP 2 LAST CDS_LIB mstr_standard
J 0
(-2850 2900);
PAINT MONO (-2850 2900);
DISPLAY INVISIBLE (-2850 2900);
FORCEPROP 1 LAST PATH I126
J 2
(-2848 2900);
DISPLAY 0.872340 (-2848 2900);
PAINT GREEN (-2848 2900);
DISPLAY INVISIBLE (-2848 2900);
FORCEADD TAP..6
R 2
(-2850 3000);
FORCEPROP 3 LASTPIN (-2900 3000) SIG_NAME M_C_DQS_DN<2>
J 0
(-2890 3010);
DISPLAY 0.659574 (-2890 3010);
PAINT MONO (-2890 3010);
DISPLAY INVISIBLE (-2890 3010);
FORCEPROP 1 LASTPIN (-2900 3000) BN 2
J 2
(-2848 3008);
DISPLAY 0.617021 (-2848 3008);
PAINT PINK (-2848 3008);
FORCEPROP 1 LAST HDL_TAP TRUE
J 2
(-3175 2875);
DISPLAY 1.595745 (-3175 2875);
PAINT GREEN (-3175 2875);
DISPLAY INVISIBLE (-3175 2875);
FORCEPROP 1 LAST BODY_TYPE PLUMBING
J 2
(-2850 2950);
DISPLAY 1.595745 (-2850 2950);
PAINT GREEN (-2850 2950);
DISPLAY INVISIBLE (-2850 2950);
FORCEPROP 2 LAST CDS_LIB mstr_standard
J 0
(-2850 3000);
PAINT MONO (-2850 3000);
DISPLAY INVISIBLE (-2850 3000);
FORCEPROP 1 LAST PATH I127
J 2
(-2848 3000);
DISPLAY 0.872340 (-2848 3000);
PAINT GREEN (-2848 3000);
DISPLAY INVISIBLE (-2848 3000);
FORCEADD TAP..6
R 2
(-2850 3050);
FORCEPROP 3 LASTPIN (-2900 3050) SIG_NAME M_C_DQS_DN<3>
J 0
(-2890 3060);
DISPLAY 0.659574 (-2890 3060);
PAINT MONO (-2890 3060);
DISPLAY INVISIBLE (-2890 3060);
FORCEPROP 1 LASTPIN (-2900 3050) BN 3
J 2
(-2848 3058);
DISPLAY 0.617021 (-2848 3058);
PAINT PINK (-2848 3058);
FORCEPROP 1 LAST HDL_TAP TRUE
J 2
(-3175 2925);
DISPLAY 1.595745 (-3175 2925);
PAINT GREEN (-3175 2925);
DISPLAY INVISIBLE (-3175 2925);
FORCEPROP 1 LAST BODY_TYPE PLUMBING
J 2
(-2850 3000);
DISPLAY 1.595745 (-2850 3000);
PAINT GREEN (-2850 3000);
DISPLAY INVISIBLE (-2850 3000);
FORCEPROP 2 LAST CDS_LIB mstr_standard
J 0
(-2850 3050);
PAINT MONO (-2850 3050);
DISPLAY INVISIBLE (-2850 3050);
FORCEPROP 1 LAST PATH I128
J 2
(-2848 3050);
DISPLAY 0.872340 (-2848 3050);
PAINT GREEN (-2848 3050);
DISPLAY INVISIBLE (-2848 3050);
FORCEADD TAP..6
R 2
(-2850 3100);
FORCEPROP 3 LASTPIN (-2900 3100) SIG_NAME M_C_DQS_DN<4>
J 0
(-2890 3110);
DISPLAY 0.659574 (-2890 3110);
PAINT MONO (-2890 3110);
DISPLAY INVISIBLE (-2890 3110);
FORCEPROP 1 LASTPIN (-2900 3100) BN 4
J 2
(-2848 3108);
DISPLAY 0.617021 (-2848 3108);
PAINT PINK (-2848 3108);
FORCEPROP 1 LAST HDL_TAP TRUE
J 2
(-3175 2975);
DISPLAY 1.595745 (-3175 2975);
PAINT GREEN (-3175 2975);
DISPLAY INVISIBLE (-3175 2975);
FORCEPROP 1 LAST BODY_TYPE PLUMBING
J 2
(-2850 3050);
DISPLAY 1.595745 (-2850 3050);
PAINT GREEN (-2850 3050);
DISPLAY INVISIBLE (-2850 3050);
FORCEPROP 2 LAST CDS_LIB mstr_standard
J 0
(-2850 3100);
PAINT MONO (-2850 3100);
DISPLAY INVISIBLE (-2850 3100);
FORCEPROP 1 LAST PATH I129
J 2
(-2848 3100);
DISPLAY 0.872340 (-2848 3100);
PAINT GREEN (-2848 3100);
DISPLAY INVISIBLE (-2848 3100);
FORCEADD TAP..6
(-5575 1100);
FORCEPROP 3 LASTPIN (-5525 1100) SIG_NAME M_C_ECC<0>
J 0
(-5515 1110);
DISPLAY 0.659574 (-5515 1110);
PAINT MONO (-5515 1110);
DISPLAY INVISIBLE (-5515 1110);
FORCEPROP 1 LASTPIN (-5525 1100) BN 0
J 0
(-5577 1108);
DISPLAY 0.617021 (-5577 1108);
PAINT PINK (-5577 1108);
FORCEPROP 1 LAST HDL_TAP TRUE
J 0
(-5250 975);
DISPLAY 1.595745 (-5250 975);
PAINT GREEN (-5250 975);
DISPLAY INVISIBLE (-5250 975);
FORCEPROP 1 LAST BODY_TYPE PLUMBING
J 0
(-5575 1050);
DISPLAY 1.595745 (-5575 1050);
PAINT GREEN (-5575 1050);
DISPLAY INVISIBLE (-5575 1050);
FORCEPROP 2 LAST CDS_LIB mstr_standard
J 0
(-5575 1100);
PAINT MONO (-5575 1100);
DISPLAY INVISIBLE (-5575 1100);
FORCEPROP 1 LAST PATH I13
J 0
(-5577 1100);
DISPLAY 0.872340 (-5577 1100);
PAINT GREEN (-5577 1100);
DISPLAY INVISIBLE (-5577 1100);
FORCEADD TAP..6
R 2
(-2850 3150);
FORCEPROP 3 LASTPIN (-2900 3150) SIG_NAME M_C_DQS_DN<5>
J 0
(-2890 3160);
DISPLAY 0.659574 (-2890 3160);
PAINT MONO (-2890 3160);
DISPLAY INVISIBLE (-2890 3160);
FORCEPROP 1 LASTPIN (-2900 3150) BN 5
J 2
(-2848 3158);
DISPLAY 0.617021 (-2848 3158);
PAINT PINK (-2848 3158);
FORCEPROP 1 LAST HDL_TAP TRUE
J 2
(-3175 3025);
DISPLAY 1.595745 (-3175 3025);
PAINT GREEN (-3175 3025);
DISPLAY INVISIBLE (-3175 3025);
FORCEPROP 1 LAST BODY_TYPE PLUMBING
J 2
(-2850 3100);
DISPLAY 1.595745 (-2850 3100);
PAINT GREEN (-2850 3100);
DISPLAY INVISIBLE (-2850 3100);
FORCEPROP 2 LAST CDS_LIB mstr_standard
J 0
(-2850 3150);
PAINT MONO (-2850 3150);
DISPLAY INVISIBLE (-2850 3150);
FORCEPROP 1 LAST PATH I130
J 2
(-2848 3150);
DISPLAY 0.872340 (-2848 3150);
PAINT GREEN (-2848 3150);
DISPLAY INVISIBLE (-2848 3150);
FORCEADD TAP..6
R 2
(-2850 3250);
FORCEPROP 3 LASTPIN (-2900 3250) SIG_NAME M_C_DQS_DN<7>
J 0
(-2890 3260);
DISPLAY 0.659574 (-2890 3260);
PAINT MONO (-2890 3260);
DISPLAY INVISIBLE (-2890 3260);
FORCEPROP 1 LASTPIN (-2900 3250) BN 7
J 2
(-2848 3258);
DISPLAY 0.617021 (-2848 3258);
PAINT PINK (-2848 3258);
FORCEPROP 1 LAST HDL_TAP TRUE
J 2
(-3175 3125);
DISPLAY 1.595745 (-3175 3125);
PAINT GREEN (-3175 3125);
DISPLAY INVISIBLE (-3175 3125);
FORCEPROP 1 LAST BODY_TYPE PLUMBING
J 2
(-2850 3200);
DISPLAY 1.595745 (-2850 3200);
PAINT GREEN (-2850 3200);
DISPLAY INVISIBLE (-2850 3200);
FORCEPROP 2 LAST CDS_LIB mstr_standard
J 0
(-2850 3250);
PAINT MONO (-2850 3250);
DISPLAY INVISIBLE (-2850 3250);
FORCEPROP 1 LAST PATH I131
J 2
(-2848 3250);
DISPLAY 0.872340 (-2848 3250);
PAINT GREEN (-2848 3250);
DISPLAY INVISIBLE (-2848 3250);
FORCEADD TAP..6
R 2
(-2850 3200);
FORCEPROP 3 LASTPIN (-2900 3200) SIG_NAME M_C_DQS_DN<6>
J 0
(-2890 3210);
DISPLAY 0.659574 (-2890 3210);
PAINT MONO (-2890 3210);
DISPLAY INVISIBLE (-2890 3210);
FORCEPROP 1 LASTPIN (-2900 3200) BN 6
J 2
(-2848 3208);
DISPLAY 0.617021 (-2848 3208);
PAINT PINK (-2848 3208);
FORCEPROP 1 LAST HDL_TAP TRUE
J 2
(-3175 3075);
DISPLAY 1.595745 (-3175 3075);
PAINT GREEN (-3175 3075);
DISPLAY INVISIBLE (-3175 3075);
FORCEPROP 1 LAST BODY_TYPE PLUMBING
J 2
(-2850 3150);
DISPLAY 1.595745 (-2850 3150);
PAINT GREEN (-2850 3150);
DISPLAY INVISIBLE (-2850 3150);
FORCEPROP 2 LAST CDS_LIB mstr_standard
J 0
(-2850 3200);
PAINT MONO (-2850 3200);
DISPLAY INVISIBLE (-2850 3200);
FORCEPROP 1 LAST PATH I132
J 2
(-2848 3200);
DISPLAY 0.872340 (-2848 3200);
PAINT GREEN (-2848 3200);
DISPLAY INVISIBLE (-2848 3200);
FORCEADD TAP..6
R 2
(-2850 3300);
FORCEPROP 3 LASTPIN (-2900 3300) SIG_NAME M_C_DQS_DN<8>
J 0
(-2890 3310);
DISPLAY 0.659574 (-2890 3310);
PAINT MONO (-2890 3310);
DISPLAY INVISIBLE (-2890 3310);
FORCEPROP 1 LASTPIN (-2900 3300) BN 8
J 2
(-2848 3308);
DISPLAY 0.617021 (-2848 3308);
PAINT PINK (-2848 3308);
FORCEPROP 1 LAST HDL_TAP TRUE
J 2
(-3175 3175);
DISPLAY 1.595745 (-3175 3175);
PAINT GREEN (-3175 3175);
DISPLAY INVISIBLE (-3175 3175);
FORCEPROP 1 LAST BODY_TYPE PLUMBING
J 2
(-2850 3250);
DISPLAY 1.595745 (-2850 3250);
PAINT GREEN (-2850 3250);
DISPLAY INVISIBLE (-2850 3250);
FORCEPROP 2 LAST CDS_LIB mstr_standard
J 0
(-2850 3300);
PAINT MONO (-2850 3300);
DISPLAY INVISIBLE (-2850 3300);
FORCEPROP 1 LAST PATH I133
J 2
(-2848 3300);
DISPLAY 0.872340 (-2848 3300);
PAINT GREEN (-2848 3300);
DISPLAY INVISIBLE (-2848 3300);
FORCEADD TAP..6
R 2
(-2850 3350);
FORCEPROP 3 LASTPIN (-2900 3350) SIG_NAME M_C_DQS_DN<9>
J 0
(-2890 3360);
DISPLAY 0.659574 (-2890 3360);
PAINT MONO (-2890 3360);
DISPLAY INVISIBLE (-2890 3360);
FORCEPROP 1 LASTPIN (-2900 3350) BN 9
J 2
(-2848 3358);
DISPLAY 0.617021 (-2848 3358);
PAINT PINK (-2848 3358);
FORCEPROP 1 LAST HDL_TAP TRUE
J 2
(-3175 3225);
DISPLAY 1.595745 (-3175 3225);
PAINT GREEN (-3175 3225);
DISPLAY INVISIBLE (-3175 3225);
FORCEPROP 1 LAST BODY_TYPE PLUMBING
J 2
(-2850 3300);
DISPLAY 1.595745 (-2850 3300);
PAINT GREEN (-2850 3300);
DISPLAY INVISIBLE (-2850 3300);
FORCEPROP 2 LAST CDS_LIB mstr_standard
J 0
(-2850 3350);
PAINT MONO (-2850 3350);
DISPLAY INVISIBLE (-2850 3350);
FORCEPROP 1 LAST PATH I134
J 2
(-2848 3350);
DISPLAY 0.872340 (-2848 3350);
PAINT GREEN (-2848 3350);
DISPLAY INVISIBLE (-2848 3350);
FORCEADD TAP..6
R 2
(-2850 3400);
FORCEPROP 3 LASTPIN (-2900 3400) SIG_NAME M_C_DQS_DN<10>
J 0
(-2890 3410);
DISPLAY 0.659574 (-2890 3410);
PAINT MONO (-2890 3410);
DISPLAY INVISIBLE (-2890 3410);
FORCEPROP 1 LASTPIN (-2900 3400) BN 10
J 2
(-2848 3408);
DISPLAY 0.617021 (-2848 3408);
PAINT PINK (-2848 3408);
FORCEPROP 1 LAST HDL_TAP TRUE
J 2
(-3175 3275);
DISPLAY 1.595745 (-3175 3275);
PAINT GREEN (-3175 3275);
DISPLAY INVISIBLE (-3175 3275);
FORCEPROP 1 LAST BODY_TYPE PLUMBING
J 2
(-2850 3350);
DISPLAY 1.595745 (-2850 3350);
PAINT GREEN (-2850 3350);
DISPLAY INVISIBLE (-2850 3350);
FORCEPROP 2 LAST CDS_LIB mstr_standard
J 0
(-2850 3400);
PAINT MONO (-2850 3400);
DISPLAY INVISIBLE (-2850 3400);
FORCEPROP 1 LAST PATH I135
J 2
(-2848 3400);
DISPLAY 0.872340 (-2848 3400);
PAINT GREEN (-2848 3400);
DISPLAY INVISIBLE (-2848 3400);
FORCEADD TAP..6
R 2
(-2850 3500);
FORCEPROP 3 LASTPIN (-2900 3500) SIG_NAME M_C_DQS_DN<12>
J 0
(-2890 3510);
DISPLAY 0.659574 (-2890 3510);
PAINT MONO (-2890 3510);
DISPLAY INVISIBLE (-2890 3510);
FORCEPROP 1 LASTPIN (-2900 3500) BN 12
J 2
(-2848 3508);
DISPLAY 0.617021 (-2848 3508);
PAINT PINK (-2848 3508);
FORCEPROP 1 LAST HDL_TAP TRUE
J 2
(-3175 3375);
DISPLAY 1.595745 (-3175 3375);
PAINT GREEN (-3175 3375);
DISPLAY INVISIBLE (-3175 3375);
FORCEPROP 1 LAST BODY_TYPE PLUMBING
J 2
(-2850 3450);
DISPLAY 1.595745 (-2850 3450);
PAINT GREEN (-2850 3450);
DISPLAY INVISIBLE (-2850 3450);
FORCEPROP 2 LAST CDS_LIB mstr_standard
J 0
(-2850 3500);
PAINT MONO (-2850 3500);
DISPLAY INVISIBLE (-2850 3500);
FORCEPROP 1 LAST PATH I136
J 2
(-2848 3500);
DISPLAY 0.872340 (-2848 3500);
PAINT GREEN (-2848 3500);
DISPLAY INVISIBLE (-2848 3500);
FORCEADD TAP..6
R 2
(-2850 3450);
FORCEPROP 3 LASTPIN (-2900 3450) SIG_NAME M_C_DQS_DN<11>
J 0
(-2890 3460);
DISPLAY 0.659574 (-2890 3460);
PAINT MONO (-2890 3460);
DISPLAY INVISIBLE (-2890 3460);
FORCEPROP 1 LASTPIN (-2900 3450) BN 11
J 2
(-2848 3458);
DISPLAY 0.617021 (-2848 3458);
PAINT PINK (-2848 3458);
FORCEPROP 1 LAST HDL_TAP TRUE
J 2
(-3175 3325);
DISPLAY 1.595745 (-3175 3325);
PAINT GREEN (-3175 3325);
DISPLAY INVISIBLE (-3175 3325);
FORCEPROP 1 LAST BODY_TYPE PLUMBING
J 2
(-2850 3400);
DISPLAY 1.595745 (-2850 3400);
PAINT GREEN (-2850 3400);
DISPLAY INVISIBLE (-2850 3400);
FORCEPROP 2 LAST CDS_LIB mstr_standard
J 0
(-2850 3450);
PAINT MONO (-2850 3450);
DISPLAY INVISIBLE (-2850 3450);
FORCEPROP 1 LAST PATH I137
J 2
(-2848 3450);
DISPLAY 0.872340 (-2848 3450);
PAINT GREEN (-2848 3450);
DISPLAY INVISIBLE (-2848 3450);
FORCEADD TAP..6
R 2
(-2850 3550);
FORCEPROP 3 LASTPIN (-2900 3550) SIG_NAME M_C_DQS_DN<13>
J 0
(-2890 3560);
DISPLAY 0.659574 (-2890 3560);
PAINT MONO (-2890 3560);
DISPLAY INVISIBLE (-2890 3560);
FORCEPROP 1 LASTPIN (-2900 3550) BN 13
J 2
(-2848 3558);
DISPLAY 0.617021 (-2848 3558);
PAINT PINK (-2848 3558);
FORCEPROP 1 LAST HDL_TAP TRUE
J 2
(-3175 3425);
DISPLAY 1.595745 (-3175 3425);
PAINT GREEN (-3175 3425);
DISPLAY INVISIBLE (-3175 3425);
FORCEPROP 1 LAST BODY_TYPE PLUMBING
J 2
(-2850 3500);
DISPLAY 1.595745 (-2850 3500);
PAINT GREEN (-2850 3500);
DISPLAY INVISIBLE (-2850 3500);
FORCEPROP 2 LAST CDS_LIB mstr_standard
J 0
(-2850 3550);
PAINT MONO (-2850 3550);
DISPLAY INVISIBLE (-2850 3550);
FORCEPROP 1 LAST PATH I138
J 2
(-2848 3550);
DISPLAY 0.872340 (-2848 3550);
PAINT GREEN (-2848 3550);
DISPLAY INVISIBLE (-2848 3550);
FORCEADD TAP..6
R 2
(-2850 3650);
FORCEPROP 3 LASTPIN (-2900 3650) SIG_NAME M_C_DQS_DN<15>
J 0
(-2890 3660);
DISPLAY 0.659574 (-2890 3660);
PAINT MONO (-2890 3660);
DISPLAY INVISIBLE (-2890 3660);
FORCEPROP 1 LASTPIN (-2900 3650) BN 15
J 2
(-2848 3658);
DISPLAY 0.617021 (-2848 3658);
PAINT PINK (-2848 3658);
FORCEPROP 1 LAST HDL_TAP TRUE
J 2
(-3175 3525);
DISPLAY 1.595745 (-3175 3525);
PAINT GREEN (-3175 3525);
DISPLAY INVISIBLE (-3175 3525);
FORCEPROP 1 LAST BODY_TYPE PLUMBING
J 2
(-2850 3600);
DISPLAY 1.595745 (-2850 3600);
PAINT GREEN (-2850 3600);
DISPLAY INVISIBLE (-2850 3600);
FORCEPROP 2 LAST CDS_LIB mstr_standard
J 0
(-2850 3650);
PAINT MONO (-2850 3650);
DISPLAY INVISIBLE (-2850 3650);
FORCEPROP 1 LAST PATH I139
J 2
(-2848 3650);
DISPLAY 0.872340 (-2848 3650);
PAINT GREEN (-2848 3650);
DISPLAY INVISIBLE (-2848 3650);
FORCEADD TAP..6
(-5575 1150);
FORCEPROP 3 LASTPIN (-5525 1150) SIG_NAME M_C_ECC<1>
J 0
(-5515 1160);
DISPLAY 0.659574 (-5515 1160);
PAINT MONO (-5515 1160);
DISPLAY INVISIBLE (-5515 1160);
FORCEPROP 1 LASTPIN (-5525 1150) BN 1
J 0
(-5577 1158);
DISPLAY 0.617021 (-5577 1158);
PAINT PINK (-5577 1158);
FORCEPROP 1 LAST HDL_TAP TRUE
J 0
(-5250 1025);
DISPLAY 1.595745 (-5250 1025);
PAINT GREEN (-5250 1025);
DISPLAY INVISIBLE (-5250 1025);
FORCEPROP 1 LAST BODY_TYPE PLUMBING
J 0
(-5575 1100);
DISPLAY 1.595745 (-5575 1100);
PAINT GREEN (-5575 1100);
DISPLAY INVISIBLE (-5575 1100);
FORCEPROP 2 LAST CDS_LIB mstr_standard
J 0
(-5575 1150);
PAINT MONO (-5575 1150);
DISPLAY INVISIBLE (-5575 1150);
FORCEPROP 1 LAST PATH I14
J 0
(-5577 1150);
DISPLAY 0.872340 (-5577 1150);
PAINT GREEN (-5577 1150);
DISPLAY INVISIBLE (-5577 1150);
FORCEADD TAP..6
R 2
(-2850 3600);
FORCEPROP 3 LASTPIN (-2900 3600) SIG_NAME M_C_DQS_DN<14>
J 0
(-2890 3610);
DISPLAY 0.659574 (-2890 3610);
PAINT MONO (-2890 3610);
DISPLAY INVISIBLE (-2890 3610);
FORCEPROP 1 LASTPIN (-2900 3600) BN 14
J 2
(-2848 3608);
DISPLAY 0.617021 (-2848 3608);
PAINT PINK (-2848 3608);
FORCEPROP 1 LAST HDL_TAP TRUE
J 2
(-3175 3475);
DISPLAY 1.595745 (-3175 3475);
PAINT GREEN (-3175 3475);
DISPLAY INVISIBLE (-3175 3475);
FORCEPROP 1 LAST BODY_TYPE PLUMBING
J 2
(-2850 3550);
DISPLAY 1.595745 (-2850 3550);
PAINT GREEN (-2850 3550);
DISPLAY INVISIBLE (-2850 3550);
FORCEPROP 2 LAST CDS_LIB mstr_standard
J 0
(-2850 3600);
PAINT MONO (-2850 3600);
DISPLAY INVISIBLE (-2850 3600);
FORCEPROP 1 LAST PATH I140
J 2
(-2848 3600);
DISPLAY 0.872340 (-2848 3600);
PAINT GREEN (-2848 3600);
DISPLAY INVISIBLE (-2848 3600);
FORCEADD TAP..6
R 2
(-2850 3750);
FORCEPROP 3 LASTPIN (-2900 3750) SIG_NAME M_C_DQS_DN<17>
J 0
(-2890 3760);
DISPLAY 0.659574 (-2890 3760);
PAINT MONO (-2890 3760);
DISPLAY INVISIBLE (-2890 3760);
FORCEPROP 1 LASTPIN (-2900 3750) BN 17
J 2
(-2848 3758);
DISPLAY 0.617021 (-2848 3758);
PAINT PINK (-2848 3758);
FORCEPROP 1 LAST HDL_TAP TRUE
J 2
(-3175 3625);
DISPLAY 1.595745 (-3175 3625);
PAINT GREEN (-3175 3625);
DISPLAY INVISIBLE (-3175 3625);
FORCEPROP 1 LAST BODY_TYPE PLUMBING
J 2
(-2850 3700);
DISPLAY 1.595745 (-2850 3700);
PAINT GREEN (-2850 3700);
DISPLAY INVISIBLE (-2850 3700);
FORCEPROP 2 LAST CDS_LIB mstr_standard
J 0
(-2850 3750);
PAINT MONO (-2850 3750);
DISPLAY INVISIBLE (-2850 3750);
FORCEPROP 1 LAST PATH I141
J 2
(-2848 3750);
DISPLAY 0.872340 (-2848 3750);
PAINT GREEN (-2848 3750);
DISPLAY INVISIBLE (-2848 3750);
FORCEADD TAP..6
R 2
(-2850 3700);
FORCEPROP 3 LASTPIN (-2900 3700) SIG_NAME M_C_DQS_DN<16>
J 0
(-2890 3710);
DISPLAY 0.659574 (-2890 3710);
PAINT MONO (-2890 3710);
DISPLAY INVISIBLE (-2890 3710);
FORCEPROP 1 LASTPIN (-2900 3700) BN 16
J 2
(-2848 3708);
DISPLAY 0.617021 (-2848 3708);
PAINT PINK (-2848 3708);
FORCEPROP 1 LAST HDL_TAP TRUE
J 2
(-3175 3575);
DISPLAY 1.595745 (-3175 3575);
PAINT GREEN (-3175 3575);
DISPLAY INVISIBLE (-3175 3575);
FORCEPROP 1 LAST BODY_TYPE PLUMBING
J 2
(-2850 3650);
DISPLAY 1.595745 (-2850 3650);
PAINT GREEN (-2850 3650);
DISPLAY INVISIBLE (-2850 3650);
FORCEPROP 2 LAST CDS_LIB mstr_standard
J 0
(-2850 3700);
PAINT MONO (-2850 3700);
DISPLAY INVISIBLE (-2850 3700);
FORCEPROP 1 LAST PATH I142
J 2
(-2848 3700);
DISPLAY 0.872340 (-2848 3700);
PAINT GREEN (-2848 3700);
DISPLAY INVISIBLE (-2848 3700);
FORCEADD TAP..6
R 2
(-2850 3900);
FORCEPROP 3 LASTPIN (-2900 3900) SIG_NAME M_C_DQS_DP<1>
J 0
(-2890 3910);
DISPLAY 0.659574 (-2890 3910);
PAINT MONO (-2890 3910);
DISPLAY INVISIBLE (-2890 3910);
FORCEPROP 1 LASTPIN (-2900 3900) BN 1
J 2
(-2848 3908);
DISPLAY 0.617021 (-2848 3908);
PAINT PINK (-2848 3908);
FORCEPROP 1 LAST HDL_TAP TRUE
J 2
(-3175 3775);
DISPLAY 1.595745 (-3175 3775);
PAINT GREEN (-3175 3775);
DISPLAY INVISIBLE (-3175 3775);
FORCEPROP 1 LAST BODY_TYPE PLUMBING
J 2
(-2850 3850);
DISPLAY 1.595745 (-2850 3850);
PAINT GREEN (-2850 3850);
DISPLAY INVISIBLE (-2850 3850);
FORCEPROP 2 LAST CDS_LIB mstr_standard
J 0
(-2850 3900);
PAINT MONO (-2850 3900);
DISPLAY INVISIBLE (-2850 3900);
FORCEPROP 1 LAST PATH I143
J 2
(-2848 3900);
DISPLAY 0.872340 (-2848 3900);
PAINT GREEN (-2848 3900);
DISPLAY INVISIBLE (-2848 3900);
FORCEADD TAP..6
R 2
(-2850 3850);
FORCEPROP 3 LASTPIN (-2900 3850) SIG_NAME M_C_DQS_DP<0>
J 0
(-2890 3860);
DISPLAY 0.659574 (-2890 3860);
PAINT MONO (-2890 3860);
DISPLAY INVISIBLE (-2890 3860);
FORCEPROP 1 LASTPIN (-2900 3850) BN 0
J 2
(-2848 3858);
DISPLAY 0.617021 (-2848 3858);
PAINT PINK (-2848 3858);
FORCEPROP 1 LAST HDL_TAP TRUE
J 2
(-3175 3725);
DISPLAY 1.595745 (-3175 3725);
PAINT GREEN (-3175 3725);
DISPLAY INVISIBLE (-3175 3725);
FORCEPROP 1 LAST BODY_TYPE PLUMBING
J 2
(-2850 3800);
DISPLAY 1.595745 (-2850 3800);
PAINT GREEN (-2850 3800);
DISPLAY INVISIBLE (-2850 3800);
FORCEPROP 2 LAST CDS_LIB mstr_standard
J 0
(-2850 3850);
PAINT MONO (-2850 3850);
DISPLAY INVISIBLE (-2850 3850);
FORCEPROP 1 LAST PATH I144
J 2
(-2848 3850);
DISPLAY 0.872340 (-2848 3850);
PAINT GREEN (-2848 3850);
DISPLAY INVISIBLE (-2848 3850);
FORCEADD TAP..6
R 2
(-2850 3950);
FORCEPROP 3 LASTPIN (-2900 3950) SIG_NAME M_C_DQS_DP<2>
J 0
(-2890 3960);
DISPLAY 0.659574 (-2890 3960);
PAINT MONO (-2890 3960);
DISPLAY INVISIBLE (-2890 3960);
FORCEPROP 1 LASTPIN (-2900 3950) BN 2
J 2
(-2848 3958);
DISPLAY 0.617021 (-2848 3958);
PAINT PINK (-2848 3958);
FORCEPROP 1 LAST HDL_TAP TRUE
J 2
(-3175 3825);
DISPLAY 1.595745 (-3175 3825);
PAINT GREEN (-3175 3825);
DISPLAY INVISIBLE (-3175 3825);
FORCEPROP 1 LAST BODY_TYPE PLUMBING
J 2
(-2850 3900);
DISPLAY 1.595745 (-2850 3900);
PAINT GREEN (-2850 3900);
DISPLAY INVISIBLE (-2850 3900);
FORCEPROP 2 LAST CDS_LIB mstr_standard
J 0
(-2850 3950);
PAINT MONO (-2850 3950);
DISPLAY INVISIBLE (-2850 3950);
FORCEPROP 1 LAST PATH I145
J 2
(-2848 3950);
DISPLAY 0.872340 (-2848 3950);
PAINT GREEN (-2848 3950);
DISPLAY INVISIBLE (-2848 3950);
FORCEADD TAP..6
R 2
(-2850 4000);
FORCEPROP 3 LASTPIN (-2900 4000) SIG_NAME M_C_DQS_DP<3>
J 0
(-2890 4010);
DISPLAY 0.659574 (-2890 4010);
PAINT MONO (-2890 4010);
DISPLAY INVISIBLE (-2890 4010);
FORCEPROP 1 LASTPIN (-2900 4000) BN 3
J 2
(-2848 4008);
DISPLAY 0.617021 (-2848 4008);
PAINT PINK (-2848 4008);
FORCEPROP 1 LAST HDL_TAP TRUE
J 2
(-3175 3875);
DISPLAY 1.595745 (-3175 3875);
PAINT GREEN (-3175 3875);
DISPLAY INVISIBLE (-3175 3875);
FORCEPROP 1 LAST BODY_TYPE PLUMBING
J 2
(-2850 3950);
DISPLAY 1.595745 (-2850 3950);
PAINT GREEN (-2850 3950);
DISPLAY INVISIBLE (-2850 3950);
FORCEPROP 2 LAST CDS_LIB mstr_standard
J 0
(-2850 4000);
PAINT MONO (-2850 4000);
DISPLAY INVISIBLE (-2850 4000);
FORCEPROP 1 LAST PATH I146
J 2
(-2848 4000);
DISPLAY 0.872340 (-2848 4000);
PAINT GREEN (-2848 4000);
DISPLAY INVISIBLE (-2848 4000);
FORCEADD OFFPAGE..2
(-2000 550);
FORCEPROP 2 LAST $XR1 48 
J 0
(-1721 550);
DISPLAY 0.638298 (-1721 550);
PAINT MONO (-1721 550);
FORCEPROP 2 LAST $XR0 47 
J 0
(-1811 550);
DISPLAY 0.638298 (-1811 550);
PAINT MONO (-1811 550);
FORCEPROP 1 LAST COMMENT_BODY TRUE
J 0
(-2045 455);
DISPLAY 1.170213 (-2045 455);
PAINT GREEN (-2045 455);
DISPLAY INVISIBLE (-2045 455);
FORCEPROP 1 LAST OFFPAGE TRUE
J 0
(-1675 425);
DISPLAY 1.170213 (-1675 425);
PAINT GREEN (-1675 425);
DISPLAY INVISIBLE (-1675 425);
FORCEPROP 2 LAST CDS_LIB mstr_standard
J 0
(-2000 550);
PAINT MONO (-2000 550);
DISPLAY INVISIBLE (-2000 550);
FORCEPROP 2 LAST PATH I147
J 0
(-1825 625);
DISPLAY 1.021277 (-1825 625);
PAINT ORANGE (-1825 625);
DISPLAY INVISIBLE (-1825 625);
FORCEADD OFFPAGE..2
(-2000 650);
FORCEPROP 2 LAST $XR1 48 
J 0
(-1721 650);
DISPLAY 0.638298 (-1721 650);
PAINT MONO (-1721 650);
FORCEPROP 2 LAST $XR0 47 
J 0
(-1811 650);
DISPLAY 0.638298 (-1811 650);
PAINT MONO (-1811 650);
FORCEPROP 1 LAST COMMENT_BODY TRUE
J 0
(-2045 555);
DISPLAY 1.170213 (-2045 555);
PAINT GREEN (-2045 555);
DISPLAY INVISIBLE (-2045 555);
FORCEPROP 1 LAST OFFPAGE TRUE
J 0
(-1675 525);
DISPLAY 1.170213 (-1675 525);
PAINT GREEN (-1675 525);
DISPLAY INVISIBLE (-1675 525);
FORCEPROP 2 LAST CDS_LIB mstr_standard
J 0
(-2000 650);
PAINT MONO (-2000 650);
DISPLAY INVISIBLE (-2000 650);
FORCEPROP 2 LAST PATH I148
J 0
(-1825 725);
DISPLAY 1.021277 (-1825 725);
PAINT ORANGE (-1825 725);
DISPLAY INVISIBLE (-1825 725);
FORCEADD OFFPAGE..4
(-2000 600);
FORCEPROP 2 LAST $XR1 48 
J 0
(-1724 600);
DISPLAY 0.638298 (-1724 600);
PAINT MONO (-1724 600);
FORCEPROP 2 LAST $XR0 47 
J 0
(-1814 600);
DISPLAY 0.638298 (-1814 600);
PAINT MONO (-1814 600);
FORCEPROP 1 LAST COMMENT_BODY TRUE
J 0
(-2025 500);
DISPLAY 1.170213 (-2025 500);
PAINT GREEN (-2025 500);
DISPLAY INVISIBLE (-2025 500);
FORCEPROP 1 LAST OFFPAGE TRUE
J 0
(-1675 475);
DISPLAY 1.170213 (-1675 475);
PAINT GREEN (-1675 475);
DISPLAY INVISIBLE (-1675 475);
FORCEPROP 2 LAST CDS_LIB mstr_standard
J 0
(-2000 600);
PAINT MONO (-2000 600);
DISPLAY INVISIBLE (-2000 600);
FORCEPROP 2 LAST PATH I149
J 0
(-1825 675);
DISPLAY 1.021277 (-1825 675);
PAINT ORANGE (-1825 675);
DISPLAY INVISIBLE (-1825 675);
FORCEADD TAP..6
(-5575 1200);
FORCEPROP 3 LASTPIN (-5525 1200) SIG_NAME M_C_ECC<2>
J 0
(-5515 1210);
DISPLAY 0.659574 (-5515 1210);
PAINT MONO (-5515 1210);
DISPLAY INVISIBLE (-5515 1210);
FORCEPROP 1 LASTPIN (-5525 1200) BN 2
J 0
(-5577 1208);
DISPLAY 0.617021 (-5577 1208);
PAINT PINK (-5577 1208);
FORCEPROP 1 LAST HDL_TAP TRUE
J 0
(-5250 1075);
DISPLAY 1.595745 (-5250 1075);
PAINT GREEN (-5250 1075);
DISPLAY INVISIBLE (-5250 1075);
FORCEPROP 1 LAST BODY_TYPE PLUMBING
J 0
(-5575 1150);
DISPLAY 1.595745 (-5575 1150);
PAINT GREEN (-5575 1150);
DISPLAY INVISIBLE (-5575 1150);
FORCEPROP 2 LAST CDS_LIB mstr_standard
J 0
(-5575 1200);
PAINT MONO (-5575 1200);
DISPLAY INVISIBLE (-5575 1200);
FORCEPROP 1 LAST PATH I15
J 0
(-5577 1200);
DISPLAY 0.872340 (-5577 1200);
PAINT GREEN (-5577 1200);
DISPLAY INVISIBLE (-5577 1200);
FORCEADD OFFPAGE..2
(-2000 950);
FORCEPROP 2 LAST $XR1 48 
J 0
(-1721 950);
DISPLAY 0.638298 (-1721 950);
PAINT MONO (-1721 950);
FORCEPROP 2 LAST $XR0 47 
J 0
(-1811 950);
DISPLAY 0.638298 (-1811 950);
PAINT MONO (-1811 950);
FORCEPROP 1 LAST COMMENT_BODY TRUE
J 0
(-2045 855);
DISPLAY 1.170213 (-2045 855);
PAINT GREEN (-2045 855);
DISPLAY INVISIBLE (-2045 855);
FORCEPROP 1 LAST OFFPAGE TRUE
J 0
(-1675 825);
DISPLAY 1.170213 (-1675 825);
PAINT GREEN (-1675 825);
DISPLAY INVISIBLE (-1675 825);
FORCEPROP 2 LAST CDS_LIB mstr_standard
J 0
(-2000 950);
PAINT MONO (-2000 950);
DISPLAY INVISIBLE (-2000 950);
FORCEPROP 2 LAST PATH I150
J 0
(-1825 1025);
DISPLAY 1.021277 (-1825 1025);
PAINT ORANGE (-1825 1025);
DISPLAY INVISIBLE (-1825 1025);
FORCEADD OFFPAGE..2
(-2000 850);
FORCEPROP 2 LAST $XR1 48 
J 0
(-1721 850);
DISPLAY 0.638298 (-1721 850);
PAINT MONO (-1721 850);
FORCEPROP 2 LAST $XR0 47 
J 0
(-1811 850);
DISPLAY 0.638298 (-1811 850);
PAINT MONO (-1811 850);
FORCEPROP 1 LAST COMMENT_BODY TRUE
J 0
(-2045 755);
DISPLAY 1.170213 (-2045 755);
PAINT GREEN (-2045 755);
DISPLAY INVISIBLE (-2045 755);
FORCEPROP 1 LAST OFFPAGE TRUE
J 0
(-1675 725);
DISPLAY 1.170213 (-1675 725);
PAINT GREEN (-1675 725);
DISPLAY INVISIBLE (-1675 725);
FORCEPROP 2 LAST CDS_LIB mstr_standard
J 0
(-2000 850);
PAINT MONO (-2000 850);
DISPLAY INVISIBLE (-2000 850);
FORCEPROP 2 LAST PATH I151
J 0
(-1825 925);
DISPLAY 1.021277 (-1825 925);
PAINT ORANGE (-1825 925);
DISPLAY INVISIBLE (-1825 925);
FORCEADD OFFPAGE..2
(-2000 1400);
FORCEPROP 2 LAST $XR1 48 
J 0
(-1721 1400);
DISPLAY 0.638298 (-1721 1400);
PAINT MONO (-1721 1400);
FORCEPROP 2 LAST $XR0 47 
J 0
(-1811 1400);
DISPLAY 0.638298 (-1811 1400);
PAINT MONO (-1811 1400);
FORCEPROP 1 LAST COMMENT_BODY TRUE
J 0
(-2045 1305);
DISPLAY 1.170213 (-2045 1305);
PAINT GREEN (-2045 1305);
DISPLAY INVISIBLE (-2045 1305);
FORCEPROP 1 LAST OFFPAGE TRUE
J 0
(-1675 1275);
DISPLAY 1.170213 (-1675 1275);
PAINT GREEN (-1675 1275);
DISPLAY INVISIBLE (-1675 1275);
FORCEPROP 2 LAST CDS_LIB mstr_standard
J 0
(-2000 1400);
PAINT MONO (-2000 1400);
DISPLAY INVISIBLE (-2000 1400);
FORCEPROP 2 LAST PATH I152
J 0
(-1825 1475);
DISPLAY 1.021277 (-1825 1475);
PAINT ORANGE (-1825 1475);
DISPLAY INVISIBLE (-1825 1475);
FORCEADD OFFPAGE..2
(-2000 1900);
FORCEPROP 2 LAST $XR1 48 
J 0
(-1721 1900);
DISPLAY 0.638298 (-1721 1900);
PAINT MONO (-1721 1900);
FORCEPROP 2 LAST $XR0 47 
J 0
(-1811 1900);
DISPLAY 0.638298 (-1811 1900);
PAINT MONO (-1811 1900);
FORCEPROP 1 LAST COMMENT_BODY TRUE
J 0
(-2045 1805);
DISPLAY 1.170213 (-2045 1805);
PAINT GREEN (-2045 1805);
DISPLAY INVISIBLE (-2045 1805);
FORCEPROP 1 LAST OFFPAGE TRUE
J 0
(-1675 1775);
DISPLAY 1.170213 (-1675 1775);
PAINT GREEN (-1675 1775);
DISPLAY INVISIBLE (-1675 1775);
FORCEPROP 2 LAST CDS_LIB mstr_standard
J 0
(-2000 1900);
PAINT MONO (-2000 1900);
DISPLAY INVISIBLE (-2000 1900);
FORCEPROP 2 LAST PATH I153
J 0
(-1825 1975);
DISPLAY 1.021277 (-1825 1975);
PAINT ORANGE (-1825 1975);
DISPLAY INVISIBLE (-1825 1975);
FORCEADD OFFPAGE..2
(-2000 1650);
FORCEPROP 2 LAST $XR1 48 
J 0
(-1721 1650);
DISPLAY 0.638298 (-1721 1650);
PAINT MONO (-1721 1650);
FORCEPROP 2 LAST $XR0 47 
J 0
(-1811 1650);
DISPLAY 0.638298 (-1811 1650);
PAINT MONO (-1811 1650);
FORCEPROP 1 LAST COMMENT_BODY TRUE
J 0
(-2045 1555);
DISPLAY 1.170213 (-2045 1555);
PAINT GREEN (-2045 1555);
DISPLAY INVISIBLE (-2045 1555);
FORCEPROP 1 LAST OFFPAGE TRUE
J 0
(-1675 1525);
DISPLAY 1.170213 (-1675 1525);
PAINT GREEN (-1675 1525);
DISPLAY INVISIBLE (-1675 1525);
FORCEPROP 2 LAST CDS_LIB mstr_standard
J 0
(-2000 1650);
PAINT MONO (-2000 1650);
DISPLAY INVISIBLE (-2000 1650);
FORCEPROP 2 LAST PATH I154
J 0
(-1825 1725);
DISPLAY 1.021277 (-1825 1725);
PAINT ORANGE (-1825 1725);
DISPLAY INVISIBLE (-1825 1725);
FORCEADD OFFPAGE..2
(-2000 2850);
FORCEPROP 2 LAST $XR1 48 
J 0
(-1721 2850);
DISPLAY 0.638298 (-1721 2850);
PAINT MONO (-1721 2850);
FORCEPROP 2 LAST $XR0 47 
J 0
(-1811 2850);
DISPLAY 0.638298 (-1811 2850);
PAINT MONO (-1811 2850);
FORCEPROP 1 LAST COMMENT_BODY TRUE
J 0
(-2045 2755);
DISPLAY 1.170213 (-2045 2755);
PAINT GREEN (-2045 2755);
DISPLAY INVISIBLE (-2045 2755);
FORCEPROP 1 LAST OFFPAGE TRUE
J 0
(-1675 2725);
DISPLAY 1.170213 (-1675 2725);
PAINT GREEN (-1675 2725);
DISPLAY INVISIBLE (-1675 2725);
FORCEPROP 2 LAST CDS_LIB mstr_standard
J 0
(-2000 2850);
PAINT MONO (-2000 2850);
DISPLAY INVISIBLE (-2000 2850);
FORCEPROP 2 LAST PATH I155
J 0
(-1825 2925);
DISPLAY 1.021277 (-1825 2925);
PAINT ORANGE (-1825 2925);
DISPLAY INVISIBLE (-1825 2925);
FORCEADD OFFPAGE..3
(-2000 3800);
FORCEPROP 2 LAST $XR1 48 
J 0
(-1696 3800);
DISPLAY 0.638298 (-1696 3800);
PAINT MONO (-1696 3800);
FORCEPROP 2 LAST $XR0 47 
J 0
(-1786 3800);
DISPLAY 0.638298 (-1786 3800);
PAINT MONO (-1786 3800);
FORCEPROP 1 LAST COMMENT_BODY TRUE
J 0
(-2050 3700);
DISPLAY 1.170213 (-2050 3700);
PAINT GREEN (-2050 3700);
DISPLAY INVISIBLE (-2050 3700);
FORCEPROP 1 LAST OFFPAGE TRUE
J 0
(-1675 3675);
DISPLAY 1.170213 (-1675 3675);
PAINT GREEN (-1675 3675);
DISPLAY INVISIBLE (-1675 3675);
FORCEPROP 2 LAST CDS_LIB mstr_standard
J 0
(-2000 3800);
PAINT MONO (-2000 3800);
DISPLAY INVISIBLE (-2000 3800);
FORCEPROP 2 LAST PATH I156
J 0
(-1800 3875);
DISPLAY 1.021277 (-1800 3875);
PAINT ORANGE (-1800 3875);
DISPLAY INVISIBLE (-1800 3875);
FORCEADD TAP..6
R 2
(-2850 4100);
FORCEPROP 3 LASTPIN (-2900 4100) SIG_NAME M_C_DQS_DP<5>
J 0
(-2890 4110);
DISPLAY 0.659574 (-2890 4110);
PAINT MONO (-2890 4110);
DISPLAY INVISIBLE (-2890 4110);
FORCEPROP 1 LASTPIN (-2900 4100) BN 5
J 2
(-2848 4108);
DISPLAY 0.617021 (-2848 4108);
PAINT PINK (-2848 4108);
FORCEPROP 1 LAST HDL_TAP TRUE
J 2
(-3175 3975);
DISPLAY 1.595745 (-3175 3975);
PAINT GREEN (-3175 3975);
DISPLAY INVISIBLE (-3175 3975);
FORCEPROP 1 LAST BODY_TYPE PLUMBING
J 2
(-2850 4050);
DISPLAY 1.595745 (-2850 4050);
PAINT GREEN (-2850 4050);
DISPLAY INVISIBLE (-2850 4050);
FORCEPROP 2 LAST CDS_LIB mstr_standard
J 0
(-2850 4100);
PAINT MONO (-2850 4100);
DISPLAY INVISIBLE (-2850 4100);
FORCEPROP 1 LAST PATH I157
J 2
(-2848 4100);
DISPLAY 0.872340 (-2848 4100);
PAINT GREEN (-2848 4100);
DISPLAY INVISIBLE (-2848 4100);
FORCEADD TAP..6
R 2
(-2850 4050);
FORCEPROP 3 LASTPIN (-2900 4050) SIG_NAME M_C_DQS_DP<4>
J 0
(-2890 4060);
DISPLAY 0.659574 (-2890 4060);
PAINT MONO (-2890 4060);
DISPLAY INVISIBLE (-2890 4060);
FORCEPROP 1 LASTPIN (-2900 4050) BN 4
J 2
(-2848 4058);
DISPLAY 0.617021 (-2848 4058);
PAINT PINK (-2848 4058);
FORCEPROP 1 LAST HDL_TAP TRUE
J 2
(-3175 3925);
DISPLAY 1.595745 (-3175 3925);
PAINT GREEN (-3175 3925);
DISPLAY INVISIBLE (-3175 3925);
FORCEPROP 1 LAST BODY_TYPE PLUMBING
J 2
(-2850 4000);
DISPLAY 1.595745 (-2850 4000);
PAINT GREEN (-2850 4000);
DISPLAY INVISIBLE (-2850 4000);
FORCEPROP 2 LAST CDS_LIB mstr_standard
J 0
(-2850 4050);
PAINT MONO (-2850 4050);
DISPLAY INVISIBLE (-2850 4050);
FORCEPROP 1 LAST PATH I158
J 2
(-2848 4050);
DISPLAY 0.872340 (-2848 4050);
PAINT GREEN (-2848 4050);
DISPLAY INVISIBLE (-2848 4050);
FORCEADD TAP..6
R 2
(-2850 4150);
FORCEPROP 3 LASTPIN (-2900 4150) SIG_NAME M_C_DQS_DP<6>
J 0
(-2890 4160);
DISPLAY 0.659574 (-2890 4160);
PAINT MONO (-2890 4160);
DISPLAY INVISIBLE (-2890 4160);
FORCEPROP 1 LASTPIN (-2900 4150) BN 6
J 2
(-2848 4158);
DISPLAY 0.617021 (-2848 4158);
PAINT PINK (-2848 4158);
FORCEPROP 1 LAST HDL_TAP TRUE
J 2
(-3175 4025);
DISPLAY 1.595745 (-3175 4025);
PAINT GREEN (-3175 4025);
DISPLAY INVISIBLE (-3175 4025);
FORCEPROP 1 LAST BODY_TYPE PLUMBING
J 2
(-2850 4100);
DISPLAY 1.595745 (-2850 4100);
PAINT GREEN (-2850 4100);
DISPLAY INVISIBLE (-2850 4100);
FORCEPROP 2 LAST CDS_LIB mstr_standard
J 0
(-2850 4150);
PAINT MONO (-2850 4150);
DISPLAY INVISIBLE (-2850 4150);
FORCEPROP 1 LAST PATH I159
J 2
(-2848 4150);
DISPLAY 0.872340 (-2848 4150);
PAINT GREEN (-2848 4150);
DISPLAY INVISIBLE (-2848 4150);
FORCEADD TAP..6
(-5575 1300);
FORCEPROP 3 LASTPIN (-5525 1300) SIG_NAME M_C_ECC<4>
J 0
(-5515 1310);
DISPLAY 0.659574 (-5515 1310);
PAINT MONO (-5515 1310);
DISPLAY INVISIBLE (-5515 1310);
FORCEPROP 1 LASTPIN (-5525 1300) BN 4
J 0
(-5577 1308);
DISPLAY 0.617021 (-5577 1308);
PAINT PINK (-5577 1308);
FORCEPROP 1 LAST HDL_TAP TRUE
J 0
(-5250 1175);
DISPLAY 1.595745 (-5250 1175);
PAINT GREEN (-5250 1175);
DISPLAY INVISIBLE (-5250 1175);
FORCEPROP 1 LAST BODY_TYPE PLUMBING
J 0
(-5575 1250);
DISPLAY 1.595745 (-5575 1250);
PAINT GREEN (-5575 1250);
DISPLAY INVISIBLE (-5575 1250);
FORCEPROP 2 LAST CDS_LIB mstr_standard
J 0
(-5575 1300);
PAINT MONO (-5575 1300);
DISPLAY INVISIBLE (-5575 1300);
FORCEPROP 1 LAST PATH I16
J 0
(-5577 1300);
DISPLAY 0.872340 (-5577 1300);
PAINT GREEN (-5577 1300);
DISPLAY INVISIBLE (-5577 1300);
FORCEADD TAP..6
R 2
(-2850 4200);
FORCEPROP 3 LASTPIN (-2900 4200) SIG_NAME M_C_DQS_DP<7>
J 0
(-2890 4210);
DISPLAY 0.659574 (-2890 4210);
PAINT MONO (-2890 4210);
DISPLAY INVISIBLE (-2890 4210);
FORCEPROP 1 LASTPIN (-2900 4200) BN 7
J 2
(-2848 4208);
DISPLAY 0.617021 (-2848 4208);
PAINT PINK (-2848 4208);
FORCEPROP 1 LAST HDL_TAP TRUE
J 2
(-3175 4075);
DISPLAY 1.595745 (-3175 4075);
PAINT GREEN (-3175 4075);
DISPLAY INVISIBLE (-3175 4075);
FORCEPROP 1 LAST BODY_TYPE PLUMBING
J 2
(-2850 4150);
DISPLAY 1.595745 (-2850 4150);
PAINT GREEN (-2850 4150);
DISPLAY INVISIBLE (-2850 4150);
FORCEPROP 2 LAST CDS_LIB mstr_standard
J 0
(-2850 4200);
PAINT MONO (-2850 4200);
DISPLAY INVISIBLE (-2850 4200);
FORCEPROP 1 LAST PATH I160
J 2
(-2848 4200);
DISPLAY 0.872340 (-2848 4200);
PAINT GREEN (-2848 4200);
DISPLAY INVISIBLE (-2848 4200);
FORCEADD TAP..6
R 2
(-2850 4250);
FORCEPROP 3 LASTPIN (-2900 4250) SIG_NAME M_C_DQS_DP<8>
J 0
(-2890 4260);
DISPLAY 0.659574 (-2890 4260);
PAINT MONO (-2890 4260);
DISPLAY INVISIBLE (-2890 4260);
FORCEPROP 1 LASTPIN (-2900 4250) BN 8
J 2
(-2848 4258);
DISPLAY 0.617021 (-2848 4258);
PAINT PINK (-2848 4258);
FORCEPROP 1 LAST HDL_TAP TRUE
J 2
(-3175 4125);
DISPLAY 1.595745 (-3175 4125);
PAINT GREEN (-3175 4125);
DISPLAY INVISIBLE (-3175 4125);
FORCEPROP 1 LAST BODY_TYPE PLUMBING
J 2
(-2850 4200);
DISPLAY 1.595745 (-2850 4200);
PAINT GREEN (-2850 4200);
DISPLAY INVISIBLE (-2850 4200);
FORCEPROP 2 LAST CDS_LIB mstr_standard
J 0
(-2850 4250);
PAINT MONO (-2850 4250);
DISPLAY INVISIBLE (-2850 4250);
FORCEPROP 1 LAST PATH I161
J 2
(-2848 4250);
DISPLAY 0.872340 (-2848 4250);
PAINT GREEN (-2848 4250);
DISPLAY INVISIBLE (-2848 4250);
FORCEADD TAP..6
R 2
(-2850 4300);
FORCEPROP 3 LASTPIN (-2900 4300) SIG_NAME M_C_DQS_DP<9>
J 0
(-2890 4310);
DISPLAY 0.659574 (-2890 4310);
PAINT MONO (-2890 4310);
DISPLAY INVISIBLE (-2890 4310);
FORCEPROP 1 LASTPIN (-2900 4300) BN 9
J 2
(-2848 4308);
DISPLAY 0.617021 (-2848 4308);
PAINT PINK (-2848 4308);
FORCEPROP 1 LAST HDL_TAP TRUE
J 2
(-3175 4175);
DISPLAY 1.595745 (-3175 4175);
PAINT GREEN (-3175 4175);
DISPLAY INVISIBLE (-3175 4175);
FORCEPROP 1 LAST BODY_TYPE PLUMBING
J 2
(-2850 4250);
DISPLAY 1.595745 (-2850 4250);
PAINT GREEN (-2850 4250);
DISPLAY INVISIBLE (-2850 4250);
FORCEPROP 2 LAST CDS_LIB mstr_standard
J 0
(-2850 4300);
PAINT MONO (-2850 4300);
DISPLAY INVISIBLE (-2850 4300);
FORCEPROP 1 LAST PATH I162
J 2
(-2848 4300);
DISPLAY 0.872340 (-2848 4300);
PAINT GREEN (-2848 4300);
DISPLAY INVISIBLE (-2848 4300);
FORCEADD TAP..6
R 2
(-2850 4350);
FORCEPROP 3 LASTPIN (-2900 4350) SIG_NAME M_C_DQS_DP<10>
J 0
(-2890 4360);
DISPLAY 0.659574 (-2890 4360);
PAINT MONO (-2890 4360);
DISPLAY INVISIBLE (-2890 4360);
FORCEPROP 1 LASTPIN (-2900 4350) BN 10
J 2
(-2848 4358);
DISPLAY 0.617021 (-2848 4358);
PAINT PINK (-2848 4358);
FORCEPROP 1 LAST HDL_TAP TRUE
J 2
(-3175 4225);
DISPLAY 1.595745 (-3175 4225);
PAINT GREEN (-3175 4225);
DISPLAY INVISIBLE (-3175 4225);
FORCEPROP 1 LAST BODY_TYPE PLUMBING
J 2
(-2850 4300);
DISPLAY 1.595745 (-2850 4300);
PAINT GREEN (-2850 4300);
DISPLAY INVISIBLE (-2850 4300);
FORCEPROP 2 LAST CDS_LIB mstr_standard
J 0
(-2850 4350);
PAINT MONO (-2850 4350);
DISPLAY INVISIBLE (-2850 4350);
FORCEPROP 1 LAST PATH I163
J 2
(-2848 4350);
DISPLAY 0.872340 (-2848 4350);
PAINT GREEN (-2848 4350);
DISPLAY INVISIBLE (-2848 4350);
FORCEADD TAP..6
R 2
(-2850 4400);
FORCEPROP 3 LASTPIN (-2900 4400) SIG_NAME M_C_DQS_DP<11>
J 0
(-2890 4410);
DISPLAY 0.659574 (-2890 4410);
PAINT MONO (-2890 4410);
DISPLAY INVISIBLE (-2890 4410);
FORCEPROP 1 LASTPIN (-2900 4400) BN 11
J 2
(-2848 4408);
DISPLAY 0.617021 (-2848 4408);
PAINT PINK (-2848 4408);
FORCEPROP 1 LAST HDL_TAP TRUE
J 2
(-3175 4275);
DISPLAY 1.595745 (-3175 4275);
PAINT GREEN (-3175 4275);
DISPLAY INVISIBLE (-3175 4275);
FORCEPROP 1 LAST BODY_TYPE PLUMBING
J 2
(-2850 4350);
DISPLAY 1.595745 (-2850 4350);
PAINT GREEN (-2850 4350);
DISPLAY INVISIBLE (-2850 4350);
FORCEPROP 2 LAST CDS_LIB mstr_standard
J 0
(-2850 4400);
PAINT MONO (-2850 4400);
DISPLAY INVISIBLE (-2850 4400);
FORCEPROP 1 LAST PATH I164
J 2
(-2848 4400);
DISPLAY 0.872340 (-2848 4400);
PAINT GREEN (-2848 4400);
DISPLAY INVISIBLE (-2848 4400);
FORCEADD TAP..6
R 2
(-2850 4450);
FORCEPROP 3 LASTPIN (-2900 4450) SIG_NAME M_C_DQS_DP<12>
J 0
(-2890 4460);
DISPLAY 0.659574 (-2890 4460);
PAINT MONO (-2890 4460);
DISPLAY INVISIBLE (-2890 4460);
FORCEPROP 1 LASTPIN (-2900 4450) BN 12
J 2
(-2848 4458);
DISPLAY 0.617021 (-2848 4458);
PAINT PINK (-2848 4458);
FORCEPROP 1 LAST HDL_TAP TRUE
J 2
(-3175 4325);
DISPLAY 1.595745 (-3175 4325);
PAINT GREEN (-3175 4325);
DISPLAY INVISIBLE (-3175 4325);
FORCEPROP 1 LAST BODY_TYPE PLUMBING
J 2
(-2850 4400);
DISPLAY 1.595745 (-2850 4400);
PAINT GREEN (-2850 4400);
DISPLAY INVISIBLE (-2850 4400);
FORCEPROP 2 LAST CDS_LIB mstr_standard
J 0
(-2850 4450);
PAINT MONO (-2850 4450);
DISPLAY INVISIBLE (-2850 4450);
FORCEPROP 1 LAST PATH I165
J 2
(-2848 4450);
DISPLAY 0.872340 (-2848 4450);
PAINT GREEN (-2848 4450);
DISPLAY INVISIBLE (-2848 4450);
FORCEADD TAP..6
R 2
(-2850 4550);
FORCEPROP 3 LASTPIN (-2900 4550) SIG_NAME M_C_DQS_DP<14>
J 0
(-2890 4560);
DISPLAY 0.659574 (-2890 4560);
PAINT MONO (-2890 4560);
DISPLAY INVISIBLE (-2890 4560);
FORCEPROP 1 LASTPIN (-2900 4550) BN 14
J 2
(-2848 4558);
DISPLAY 0.617021 (-2848 4558);
PAINT PINK (-2848 4558);
FORCEPROP 1 LAST HDL_TAP TRUE
J 2
(-3175 4425);
DISPLAY 1.595745 (-3175 4425);
PAINT GREEN (-3175 4425);
DISPLAY INVISIBLE (-3175 4425);
FORCEPROP 1 LAST BODY_TYPE PLUMBING
J 2
(-2850 4500);
DISPLAY 1.595745 (-2850 4500);
PAINT GREEN (-2850 4500);
DISPLAY INVISIBLE (-2850 4500);
FORCEPROP 2 LAST CDS_LIB mstr_standard
J 0
(-2850 4550);
PAINT MONO (-2850 4550);
DISPLAY INVISIBLE (-2850 4550);
FORCEPROP 1 LAST PATH I166
J 2
(-2848 4550);
DISPLAY 0.872340 (-2848 4550);
PAINT GREEN (-2848 4550);
DISPLAY INVISIBLE (-2848 4550);
FORCEADD TAP..6
R 2
(-2850 4500);
FORCEPROP 3 LASTPIN (-2900 4500) SIG_NAME M_C_DQS_DP<13>
J 0
(-2890 4510);
DISPLAY 0.659574 (-2890 4510);
PAINT MONO (-2890 4510);
DISPLAY INVISIBLE (-2890 4510);
FORCEPROP 1 LASTPIN (-2900 4500) BN 13
J 2
(-2848 4508);
DISPLAY 0.617021 (-2848 4508);
PAINT PINK (-2848 4508);
FORCEPROP 1 LAST HDL_TAP TRUE
J 2
(-3175 4375);
DISPLAY 1.595745 (-3175 4375);
PAINT GREEN (-3175 4375);
DISPLAY INVISIBLE (-3175 4375);
FORCEPROP 1 LAST BODY_TYPE PLUMBING
J 2
(-2850 4450);
DISPLAY 1.595745 (-2850 4450);
PAINT GREEN (-2850 4450);
DISPLAY INVISIBLE (-2850 4450);
FORCEPROP 2 LAST CDS_LIB mstr_standard
J 0
(-2850 4500);
PAINT MONO (-2850 4500);
DISPLAY INVISIBLE (-2850 4500);
FORCEPROP 1 LAST PATH I167
J 2
(-2848 4500);
DISPLAY 0.872340 (-2848 4500);
PAINT GREEN (-2848 4500);
DISPLAY INVISIBLE (-2848 4500);
FORCEADD TAP..6
R 2
(-2850 4600);
FORCEPROP 3 LASTPIN (-2900 4600) SIG_NAME M_C_DQS_DP<15>
J 0
(-2890 4610);
DISPLAY 0.659574 (-2890 4610);
PAINT MONO (-2890 4610);
DISPLAY INVISIBLE (-2890 4610);
FORCEPROP 1 LASTPIN (-2900 4600) BN 15
J 2
(-2848 4608);
DISPLAY 0.617021 (-2848 4608);
PAINT PINK (-2848 4608);
FORCEPROP 1 LAST HDL_TAP TRUE
J 2
(-3175 4475);
DISPLAY 1.595745 (-3175 4475);
PAINT GREEN (-3175 4475);
DISPLAY INVISIBLE (-3175 4475);
FORCEPROP 1 LAST BODY_TYPE PLUMBING
J 2
(-2850 4550);
DISPLAY 1.595745 (-2850 4550);
PAINT GREEN (-2850 4550);
DISPLAY INVISIBLE (-2850 4550);
FORCEPROP 2 LAST CDS_LIB mstr_standard
J 0
(-2850 4600);
PAINT MONO (-2850 4600);
DISPLAY INVISIBLE (-2850 4600);
FORCEPROP 1 LAST PATH I168
J 2
(-2848 4600);
DISPLAY 0.872340 (-2848 4600);
PAINT GREEN (-2848 4600);
DISPLAY INVISIBLE (-2848 4600);
FORCEADD TAP..6
R 2
(-2850 4650);
FORCEPROP 3 LASTPIN (-2900 4650) SIG_NAME M_C_DQS_DP<16>
J 0
(-2890 4660);
DISPLAY 0.659574 (-2890 4660);
PAINT MONO (-2890 4660);
DISPLAY INVISIBLE (-2890 4660);
FORCEPROP 1 LASTPIN (-2900 4650) BN 16
J 2
(-2848 4658);
DISPLAY 0.617021 (-2848 4658);
PAINT PINK (-2848 4658);
FORCEPROP 1 LAST HDL_TAP TRUE
J 2
(-3175 4525);
DISPLAY 1.595745 (-3175 4525);
PAINT GREEN (-3175 4525);
DISPLAY INVISIBLE (-3175 4525);
FORCEPROP 1 LAST BODY_TYPE PLUMBING
J 2
(-2850 4600);
DISPLAY 1.595745 (-2850 4600);
PAINT GREEN (-2850 4600);
DISPLAY INVISIBLE (-2850 4600);
FORCEPROP 2 LAST CDS_LIB mstr_standard
J 0
(-2850 4650);
PAINT MONO (-2850 4650);
DISPLAY INVISIBLE (-2850 4650);
FORCEPROP 1 LAST PATH I169
J 2
(-2848 4650);
DISPLAY 0.872340 (-2848 4650);
PAINT GREEN (-2848 4650);
DISPLAY INVISIBLE (-2848 4650);
FORCEADD TAP..6
(-5575 1250);
FORCEPROP 3 LASTPIN (-5525 1250) SIG_NAME M_C_ECC<3>
J 0
(-5515 1260);
DISPLAY 0.659574 (-5515 1260);
PAINT MONO (-5515 1260);
DISPLAY INVISIBLE (-5515 1260);
FORCEPROP 1 LASTPIN (-5525 1250) BN 3
J 0
(-5577 1258);
DISPLAY 0.617021 (-5577 1258);
PAINT PINK (-5577 1258);
FORCEPROP 1 LAST HDL_TAP TRUE
J 0
(-5250 1125);
DISPLAY 1.595745 (-5250 1125);
PAINT GREEN (-5250 1125);
DISPLAY INVISIBLE (-5250 1125);
FORCEPROP 1 LAST BODY_TYPE PLUMBING
J 0
(-5575 1200);
DISPLAY 1.595745 (-5575 1200);
PAINT GREEN (-5575 1200);
DISPLAY INVISIBLE (-5575 1200);
FORCEPROP 2 LAST CDS_LIB mstr_standard
J 0
(-5575 1250);
PAINT MONO (-5575 1250);
DISPLAY INVISIBLE (-5575 1250);
FORCEPROP 1 LAST PATH I17
J 0
(-5577 1250);
DISPLAY 0.872340 (-5577 1250);
PAINT GREEN (-5577 1250);
DISPLAY INVISIBLE (-5577 1250);
FORCEADD TAP..6
R 2
(-2850 4700);
FORCEPROP 3 LASTPIN (-2900 4700) SIG_NAME M_C_DQS_DP<17>
J 0
(-2890 4710);
DISPLAY 0.659574 (-2890 4710);
PAINT MONO (-2890 4710);
DISPLAY INVISIBLE (-2890 4710);
FORCEPROP 1 LASTPIN (-2900 4700) BN 17
J 2
(-2848 4708);
DISPLAY 0.617021 (-2848 4708);
PAINT PINK (-2848 4708);
FORCEPROP 1 LAST HDL_TAP TRUE
J 2
(-3175 4575);
DISPLAY 1.595745 (-3175 4575);
PAINT GREEN (-3175 4575);
DISPLAY INVISIBLE (-3175 4575);
FORCEPROP 1 LAST BODY_TYPE PLUMBING
J 2
(-2850 4650);
DISPLAY 1.595745 (-2850 4650);
PAINT GREEN (-2850 4650);
DISPLAY INVISIBLE (-2850 4650);
FORCEPROP 2 LAST CDS_LIB mstr_standard
J 2
(-2850 4700);
PAINT MONO (-2850 4700);
DISPLAY INVISIBLE (-2850 4700);
FORCEPROP 1 LAST PATH I170
J 2
(-2848 4700);
DISPLAY 0.872340 (-2848 4700);
PAINT GREEN (-2848 4700);
DISPLAY INVISIBLE (-2848 4700);
FORCEADD OFFPAGE..3
(-2000 4775);
FORCEPROP 2 LAST $XR1 48 
J 0
(-1696 4775);
DISPLAY 0.638298 (-1696 4775);
PAINT MONO (-1696 4775);
FORCEPROP 2 LAST $XR0 47 
J 0
(-1786 4775);
DISPLAY 0.638298 (-1786 4775);
PAINT MONO (-1786 4775);
FORCEPROP 1 LAST COMMENT_BODY TRUE
J 0
(-2050 4675);
DISPLAY 1.170213 (-2050 4675);
PAINT GREEN (-2050 4675);
DISPLAY INVISIBLE (-2050 4675);
FORCEPROP 1 LAST OFFPAGE TRUE
J 0
(-1675 4650);
DISPLAY 1.170213 (-1675 4650);
PAINT GREEN (-1675 4650);
DISPLAY INVISIBLE (-1675 4650);
FORCEPROP 2 LAST CDS_LIB mstr_standard
J 0
(-2000 4775);
PAINT MONO (-2000 4775);
DISPLAY INVISIBLE (-2000 4775);
FORCEPROP 2 LAST PATH I171
J 0
(-1800 4850);
DISPLAY 1.021277 (-1800 4850);
PAINT ORANGE (-1800 4850);
DISPLAY INVISIBLE (-1800 4850);
FORCEADD SKX_EXT_B..5
(-4175 2600);
FORCEPROP 1 LAST LOCATION U5D1
J 0
(-4975 4950);
DISPLAY 0.617021 (-4975 4950);
PAINT AQUA (-4975 4950);
FORCEPROP 1 LAST PART_NUMBER TBD
J 0
(-4975 350);
DISPLAY 0.617021 (-4975 350);
PAINT BLUE (-4975 350);
FORCEPROP 1 LAST MATERIAL IC
J 0
(-4975 4900);
DISPLAY 0.617021 (-4975 4900);
PAINT SKYBLUE (-4975 4900);
FORCEPROP 2 LASTPIN (-3325 550) $PN V53
J 0
(-3315 560);
DISPLAY 0.617021 (-3315 560);
PAINT ORANGE (-3315 560);
FORCEPROP 2 LASTPIN (-3325 1600) $PN AB47
J 0
(-3315 1610);
DISPLAY 0.617021 (-3315 1610);
PAINT ORANGE (-3315 1610);
FORCEPROP 2 LASTPIN (-3325 1550) $PN V49
J 0
(-3315 1560);
DISPLAY 0.617021 (-3315 1560);
PAINT ORANGE (-3315 1560);
FORCEPROP 2 LASTPIN (-3325 1500) $PN AA48
J 0
(-3315 1510);
DISPLAY 0.617021 (-3315 1510);
PAINT ORANGE (-3315 1510);
FORCEPROP 2 LASTPIN (-3325 1450) $PN AA50
J 0
(-3315 1460);
DISPLAY 0.617021 (-3315 1460);
PAINT ORANGE (-3315 1460);
FORCEPROP 2 LASTPIN (-3325 2800) $PN AC46
J 0
(-3315 2810);
DISPLAY 0.617021 (-3315 2810);
PAINT ORANGE (-3315 2810);
FORCEPROP 2 LASTPIN (-3325 2750) $PN AA52
J 0
(-3315 2760);
DISPLAY 0.617021 (-3315 2760);
PAINT ORANGE (-3315 2760);
FORCEPROP 2 LASTPIN (-3325 2700) $PN AE54
J 0
(-3315 2710);
DISPLAY 0.617021 (-3315 2710);
PAINT ORANGE (-3315 2710);
FORCEPROP 2 LASTPIN (-3325 2650) $PN W50
J 0
(-3315 2660);
DISPLAY 0.617021 (-3315 2660);
PAINT ORANGE (-3315 2660);
FORCEPROP 2 LASTPIN (-3325 2600) $PN AD53
J 0
(-3315 2610);
DISPLAY 0.617021 (-3315 2610);
PAINT ORANGE (-3315 2610);
FORCEPROP 2 LASTPIN (-3325 2550) $PN AG62
J 0
(-3315 2560);
DISPLAY 0.617021 (-3315 2560);
PAINT ORANGE (-3315 2560);
FORCEPROP 2 LASTPIN (-3325 2500) $PN AG60
J 0
(-3315 2510);
DISPLAY 0.617021 (-3315 2510);
PAINT ORANGE (-3315 2510);
FORCEPROP 2 LASTPIN (-3325 2450) $PN AD55
J 0
(-3315 2460);
DISPLAY 0.617021 (-3315 2460);
PAINT ORANGE (-3315 2460);
FORCEPROP 2 LASTPIN (-3325 2400) $PN AG58
J 0
(-3315 2410);
DISPLAY 0.617021 (-3315 2410);
PAINT ORANGE (-3315 2410);
FORCEPROP 2 LASTPIN (-3325 2350) $PN AD59
J 0
(-3315 2360);
DISPLAY 0.617021 (-3315 2360);
PAINT ORANGE (-3315 2360);
FORCEPROP 2 LASTPIN (-3325 2300) $PN AE60
J 0
(-3315 2310);
DISPLAY 0.617021 (-3315 2310);
PAINT ORANGE (-3315 2310);
FORCEPROP 2 LASTPIN (-3325 2250) $PN AB59
J 0
(-3315 2260);
DISPLAY 0.617021 (-3315 2260);
PAINT ORANGE (-3315 2260);
FORCEPROP 2 LASTPIN (-3325 2200) $PN V59
J 0
(-3315 2210);
DISPLAY 0.617021 (-3315 2210);
PAINT ORANGE (-3315 2210);
FORCEPROP 2 LASTPIN (-3325 2150) $PN AA58
J 0
(-3315 2160);
DISPLAY 0.617021 (-3315 2160);
PAINT ORANGE (-3315 2160);
FORCEPROP 2 LASTPIN (-3325 2100) $PN W58
J 0
(-3315 2110);
DISPLAY 0.617021 (-3315 2110);
PAINT ORANGE (-3315 2110);
FORCEPROP 2 LASTPIN (-3325 2050) $PN AD57
J 0
(-3315 2060);
DISPLAY 0.617021 (-3315 2060);
PAINT ORANGE (-3315 2060);
FORCEPROP 2 LASTPIN (-3325 2000) $PN AE58
J 0
(-3315 2010);
DISPLAY 0.617021 (-3315 2010);
PAINT ORANGE (-3315 2010);
FORCEPROP 2 LASTPIN (-3325 1950) $PN AB53
J 0
(-3315 1960);
DISPLAY 0.617021 (-3315 1960);
PAINT ORANGE (-3315 1960);
FORCEPROP 2 LASTPIN (-5025 1450) $PN BA70
J 2
(-5035 1460);
DISPLAY 0.617021 (-5035 1460);
PAINT ORANGE (-5035 1460);
FORCEPROP 2 LASTPIN (-5025 1400) $PN AU70
J 2
(-5035 1410);
DISPLAY 0.617021 (-5035 1410);
PAINT ORANGE (-5035 1410);
FORCEPROP 2 LASTPIN (-5025 1350) $PN AY73
J 2
(-5035 1360);
DISPLAY 0.617021 (-5035 1360);
PAINT ORANGE (-5035 1360);
FORCEPROP 2 LASTPIN (-5025 1300) $PN AV73
J 2
(-5035 1310);
DISPLAY 0.617021 (-5035 1310);
PAINT ORANGE (-5035 1310);
FORCEPROP 2 LASTPIN (-5025 1250) $PN AY69
J 2
(-5035 1260);
DISPLAY 0.617021 (-5035 1260);
PAINT ORANGE (-5035 1260);
FORCEPROP 2 LASTPIN (-5025 1200) $PN AV69
J 2
(-5035 1210);
DISPLAY 0.617021 (-5035 1210);
PAINT ORANGE (-5035 1210);
FORCEPROP 2 LASTPIN (-5025 1150) $PN BA72
J 2
(-5035 1160);
DISPLAY 0.617021 (-5035 1160);
PAINT ORANGE (-5035 1160);
FORCEPROP 2 LASTPIN (-3325 4700) $PN AV71
J 0
(-3315 4710);
DISPLAY 0.617021 (-3315 4710);
PAINT ORANGE (-3315 4710);
FORCEPROP 2 LASTPIN (-3325 4650) $PN AE24
J 0
(-3315 4660);
DISPLAY 0.617021 (-3315 4660);
PAINT ORANGE (-3315 4660);
FORCEPROP 2 LASTPIN (-3325 4600) $PN AE30
J 0
(-3315 4610);
DISPLAY 0.617021 (-3315 4610);
PAINT ORANGE (-3315 4610);
FORCEPROP 2 LASTPIN (-3325 4550) $PN V33
J 0
(-3315 4560);
DISPLAY 0.617021 (-3315 4560);
PAINT ORANGE (-3315 4560);
FORCEPROP 2 LASTPIN (-3325 4500) $PN V39
J 0
(-3315 4510);
DISPLAY 0.617021 (-3315 4510);
PAINT ORANGE (-3315 4510);
FORCEPROP 2 LASTPIN (-3325 4450) $PN AN66
J 0
(-3315 4460);
DISPLAY 0.617021 (-3315 4460);
PAINT ORANGE (-3315 4460);
FORCEPROP 2 LASTPIN (-3325 4400) $PN V71
J 0
(-3315 4410);
DISPLAY 0.617021 (-3315 4410);
PAINT ORANGE (-3315 4410);
FORCEPROP 2 LASTPIN (-3325 4350) $PN AC76
J 0
(-3315 4360);
DISPLAY 0.617021 (-3315 4360);
PAINT ORANGE (-3315 4360);
FORCEPROP 2 LASTPIN (-3325 4300) $PN AN76
J 0
(-3315 4310);
DISPLAY 0.617021 (-3315 4310);
PAINT ORANGE (-3315 4310);
FORCEPROP 2 LASTPIN (-3325 4250) $PN AY71
J 0
(-3315 4260);
DISPLAY 0.617021 (-3315 4260);
PAINT ORANGE (-3315 4260);
FORCEPROP 2 LASTPIN (-3325 4200) $PN AG24
J 0
(-3315 4210);
DISPLAY 0.617021 (-3315 4210);
PAINT ORANGE (-3315 4210);
FORCEPROP 2 LASTPIN (-3325 4150) $PN AG30
J 0
(-3315 4160);
DISPLAY 0.617021 (-3315 4160);
PAINT ORANGE (-3315 4160);
FORCEPROP 2 LASTPIN (-3325 4100) $PN Y33
J 0
(-3315 4110);
DISPLAY 0.617021 (-3315 4110);
PAINT ORANGE (-3315 4110);
FORCEPROP 2 LASTPIN (-3325 4050) $PN Y39
J 0
(-3315 4060);
DISPLAY 0.617021 (-3315 4060);
PAINT ORANGE (-3315 4060);
FORCEPROP 2 LASTPIN (-3325 4000) $PN AR66
J 0
(-3315 4010);
DISPLAY 0.617021 (-3315 4010);
PAINT ORANGE (-3315 4010);
FORCEPROP 2 LASTPIN (-3325 3950) $PN W70
J 0
(-3315 3960);
DISPLAY 0.617021 (-3315 3960);
PAINT ORANGE (-3315 3960);
FORCEPROP 2 LASTPIN (-3325 3900) $PN AB75
J 0
(-3315 3910);
DISPLAY 0.617021 (-3315 3910);
PAINT ORANGE (-3315 3910);
FORCEPROP 2 LASTPIN (-3325 3850) $PN AM75
J 0
(-3315 3860);
DISPLAY 0.617021 (-3315 3860);
PAINT ORANGE (-3315 3860);
FORCEPROP 2 LASTPIN (-3325 3750) $PN AT71
J 0
(-3315 3760);
DISPLAY 0.617021 (-3315 3760);
PAINT ORANGE (-3315 3760);
FORCEPROP 2 LASTPIN (-3325 3700) $PN AC24
J 0
(-3315 3710);
DISPLAY 0.617021 (-3315 3710);
PAINT ORANGE (-3315 3710);
FORCEPROP 2 LASTPIN (-3325 3650) $PN AC30
J 0
(-3315 3660);
DISPLAY 0.617021 (-3315 3660);
PAINT ORANGE (-3315 3660);
FORCEPROP 2 LASTPIN (-3325 3600) $PN T33
J 0
(-3315 3610);
DISPLAY 0.617021 (-3315 3610);
PAINT ORANGE (-3315 3610);
FORCEPROP 2 LASTPIN (-3325 3550) $PN T39
J 0
(-3315 3560);
DISPLAY 0.617021 (-3315 3560);
PAINT ORANGE (-3315 3560);
FORCEPROP 2 LASTPIN (-3325 3500) $PN AL66
J 0
(-3315 3510);
DISPLAY 0.617021 (-3315 3510);
PAINT ORANGE (-3315 3510);
FORCEPROP 2 LASTPIN (-3325 3450) $PN U72
J 0
(-3315 3460);
DISPLAY 0.617021 (-3315 3460);
PAINT ORANGE (-3315 3460);
FORCEPROP 2 LASTPIN (-3325 3400) $PN AD77
J 0
(-3315 3410);
DISPLAY 0.617021 (-3315 3410);
PAINT ORANGE (-3315 3410);
FORCEPROP 2 LASTPIN (-3325 3350) $PN AP77
J 0
(-3315 3360);
DISPLAY 0.617021 (-3315 3360);
PAINT ORANGE (-3315 3360);
FORCEPROP 2 LASTPIN (-3325 3300) $PN BB71
J 0
(-3315 3310);
DISPLAY 0.617021 (-3315 3310);
PAINT ORANGE (-3315 3310);
FORCEPROP 2 LASTPIN (-3325 3250) $PN AJ24
J 0
(-3315 3260);
DISPLAY 0.617021 (-3315 3260);
PAINT ORANGE (-3315 3260);
FORCEPROP 2 LASTPIN (-3325 3200) $PN AJ30
J 0
(-3315 3210);
DISPLAY 0.617021 (-3315 3210);
PAINT ORANGE (-3315 3210);
FORCEPROP 2 LASTPIN (-3325 3150) $PN AB33
J 0
(-3315 3160);
DISPLAY 0.617021 (-3315 3160);
PAINT ORANGE (-3315 3160);
FORCEPROP 2 LASTPIN (-3325 3100) $PN AB39
J 0
(-3315 3110);
DISPLAY 0.617021 (-3315 3110);
PAINT ORANGE (-3315 3110);
FORCEPROP 2 LASTPIN (-3325 3050) $PN AU66
J 0
(-3315 3060);
DISPLAY 0.617021 (-3315 3060);
PAINT ORANGE (-3315 3060);
FORCEPROP 2 LASTPIN (-3325 3000) $PN Y69
J 0
(-3315 3010);
DISPLAY 0.617021 (-3315 3010);
PAINT ORANGE (-3315 3010);
FORCEPROP 2 LASTPIN (-3325 2950) $PN AA74
J 0
(-3315 2960);
DISPLAY 0.617021 (-3315 2960);
PAINT ORANGE (-3315 2960);
FORCEPROP 2 LASTPIN (-3325 2900) $PN AL74
J 0
(-3315 2910);
DISPLAY 0.617021 (-3315 2910);
PAINT ORANGE (-3315 2910);
FORCEPROP 2 LASTPIN (-5025 4700) $PN AH23
J 2
(-5035 4710);
DISPLAY 0.617021 (-5035 4710);
PAINT ORANGE (-5035 4710);
FORCEPROP 2 LASTPIN (-5025 4650) $PN AD23
J 2
(-5035 4660);
DISPLAY 0.617021 (-5035 4660);
PAINT ORANGE (-5035 4660);
FORCEPROP 2 LASTPIN (-5025 4600) $PN AG26
J 2
(-5035 4610);
DISPLAY 0.617021 (-5035 4610);
PAINT ORANGE (-5035 4610);
FORCEPROP 2 LASTPIN (-5025 4550) $PN AE26
J 2
(-5035 4560);
DISPLAY 0.617021 (-5035 4560);
PAINT ORANGE (-5035 4560);
FORCEPROP 2 LASTPIN (-5025 4500) $PN AG22
J 2
(-5035 4510);
DISPLAY 0.617021 (-5035 4510);
PAINT ORANGE (-5035 4510);
FORCEPROP 2 LASTPIN (-5025 4450) $PN AE22
J 2
(-5035 4460);
DISPLAY 0.617021 (-5035 4460);
PAINT ORANGE (-5035 4460);
FORCEPROP 2 LASTPIN (-5025 4400) $PN AH25
J 2
(-5035 4410);
DISPLAY 0.617021 (-5035 4410);
PAINT ORANGE (-5035 4410);
FORCEPROP 2 LASTPIN (-5025 4350) $PN AD25
J 2
(-5035 4360);
DISPLAY 0.617021 (-5035 4360);
PAINT ORANGE (-5035 4360);
FORCEPROP 2 LASTPIN (-5025 4300) $PN AH29
J 2
(-5035 4310);
DISPLAY 0.617021 (-5035 4310);
PAINT ORANGE (-5035 4310);
FORCEPROP 2 LASTPIN (-5025 4250) $PN AD29
J 2
(-5035 4260);
DISPLAY 0.617021 (-5035 4260);
PAINT ORANGE (-5035 4260);
FORCEPROP 2 LASTPIN (-5025 4200) $PN AG32
J 2
(-5035 4210);
DISPLAY 0.617021 (-5035 4210);
PAINT ORANGE (-5035 4210);
FORCEPROP 2 LASTPIN (-5025 4150) $PN AE32
J 2
(-5035 4160);
DISPLAY 0.617021 (-5035 4160);
PAINT ORANGE (-5035 4160);
FORCEPROP 2 LASTPIN (-5025 4100) $PN AG28
J 2
(-5035 4110);
DISPLAY 0.617021 (-5035 4110);
PAINT ORANGE (-5035 4110);
FORCEPROP 2 LASTPIN (-5025 4050) $PN AE28
J 2
(-5035 4060);
DISPLAY 0.617021 (-5035 4060);
PAINT ORANGE (-5035 4060);
FORCEPROP 2 LASTPIN (-5025 4000) $PN AH31
J 2
(-5035 4010);
DISPLAY 0.617021 (-5035 4010);
PAINT ORANGE (-5035 4010);
FORCEPROP 2 LASTPIN (-5025 3950) $PN AD31
J 2
(-5035 3960);
DISPLAY 0.617021 (-5035 3960);
PAINT ORANGE (-5035 3960);
FORCEPROP 2 LASTPIN (-5025 3900) $PN AA32
J 2
(-5035 3910);
DISPLAY 0.617021 (-5035 3910);
PAINT ORANGE (-5035 3910);
FORCEPROP 2 LASTPIN (-5025 3850) $PN U32
J 2
(-5035 3860);
DISPLAY 0.617021 (-5035 3860);
PAINT ORANGE (-5035 3860);
FORCEPROP 2 LASTPIN (-5025 3800) $PN Y35
J 2
(-5035 3810);
DISPLAY 0.617021 (-5035 3810);
PAINT ORANGE (-5035 3810);
FORCEPROP 2 LASTPIN (-5025 3750) $PN V35
J 2
(-5035 3760);
DISPLAY 0.617021 (-5035 3760);
PAINT ORANGE (-5035 3760);
FORCEPROP 2 LASTPIN (-5025 3700) $PN Y31
J 2
(-5035 3710);
DISPLAY 0.617021 (-5035 3710);
PAINT ORANGE (-5035 3710);
FORCEPROP 2 LASTPIN (-5025 3650) $PN V31
J 2
(-5035 3660);
DISPLAY 0.617021 (-5035 3660);
PAINT ORANGE (-5035 3660);
FORCEPROP 2 LASTPIN (-5025 3600) $PN AA34
J 2
(-5035 3610);
DISPLAY 0.617021 (-5035 3610);
PAINT ORANGE (-5035 3610);
FORCEPROP 2 LASTPIN (-5025 3550) $PN U34
J 2
(-5035 3560);
DISPLAY 0.617021 (-5035 3560);
PAINT ORANGE (-5035 3560);
FORCEPROP 2 LASTPIN (-5025 3500) $PN AA38
J 2
(-5035 3510);
DISPLAY 0.617021 (-5035 3510);
PAINT ORANGE (-5035 3510);
FORCEPROP 2 LASTPIN (-5025 3450) $PN U38
J 2
(-5035 3460);
DISPLAY 0.617021 (-5035 3460);
PAINT ORANGE (-5035 3460);
FORCEPROP 2 LASTPIN (-5025 3400) $PN Y41
J 2
(-5035 3410);
DISPLAY 0.617021 (-5035 3410);
PAINT ORANGE (-5035 3410);
FORCEPROP 2 LASTPIN (-5025 3350) $PN V41
J 2
(-5035 3360);
DISPLAY 0.617021 (-5035 3360);
PAINT ORANGE (-5035 3360);
FORCEPROP 2 LASTPIN (-5025 3300) $PN Y37
J 2
(-5035 3310);
DISPLAY 0.617021 (-5035 3310);
PAINT ORANGE (-5035 3310);
FORCEPROP 2 LASTPIN (-5025 3250) $PN V37
J 2
(-5035 3260);
DISPLAY 0.617021 (-5035 3260);
PAINT ORANGE (-5035 3260);
FORCEPROP 2 LASTPIN (-5025 3200) $PN AA40
J 2
(-5035 3210);
DISPLAY 0.617021 (-5035 3210);
PAINT ORANGE (-5035 3210);
FORCEPROP 2 LASTPIN (-5025 3150) $PN U40
J 2
(-5035 3160);
DISPLAY 0.617021 (-5035 3160);
PAINT ORANGE (-5035 3160);
FORCEPROP 2 LASTPIN (-5025 3100) $PN AT65
J 2
(-5035 3110);
DISPLAY 0.617021 (-5035 3110);
PAINT ORANGE (-5035 3110);
FORCEPROP 2 LASTPIN (-5025 3050) $PN AM65
J 2
(-5035 3060);
DISPLAY 0.617021 (-5035 3060);
PAINT ORANGE (-5035 3060);
FORCEPROP 2 LASTPIN (-5025 3000) $PN AR68
J 2
(-5035 3010);
DISPLAY 0.617021 (-5035 3010);
PAINT ORANGE (-5035 3010);
FORCEPROP 2 LASTPIN (-5025 2850) $PN AN64
J 2
(-5035 2860);
DISPLAY 0.617021 (-5035 2860);
PAINT ORANGE (-5035 2860);
FORCEPROP 2 LASTPIN (-5025 2800) $PN AT67
J 2
(-5035 2810);
DISPLAY 0.617021 (-5035 2810);
PAINT ORANGE (-5035 2810);
FORCEPROP 2 LASTPIN (-5025 2750) $PN AM67
J 2
(-5035 2760);
DISPLAY 0.617021 (-5035 2760);
PAINT ORANGE (-5035 2760);
FORCEPROP 2 LASTPIN (-5025 2700) $PN V69
J 2
(-5035 2710);
DISPLAY 0.617021 (-5035 2710);
PAINT ORANGE (-5035 2710);
FORCEPROP 2 LASTPIN (-5025 2650) $PN T71
J 2
(-5035 2660);
DISPLAY 0.617021 (-5035 2660);
PAINT ORANGE (-5035 2660);
FORCEPROP 2 LASTPIN (-5025 2600) $PN AB71
J 2
(-5035 2610);
DISPLAY 0.617021 (-5035 2610);
PAINT ORANGE (-5035 2610);
FORCEPROP 2 LASTPIN (-5025 2550) $PN AA72
J 2
(-5035 2560);
DISPLAY 0.617021 (-5035 2560);
PAINT ORANGE (-5035 2560);
FORCEPROP 2 LASTPIN (-5025 2500) $PN T69
J 2
(-5035 2510);
DISPLAY 0.617021 (-5035 2510);
PAINT ORANGE (-5035 2510);
FORCEPROP 2 LASTPIN (-5025 2450) $PN R70
J 2
(-5035 2460);
DISPLAY 0.617021 (-5035 2460);
PAINT ORANGE (-5035 2460);
FORCEPROP 2 LASTPIN (-5025 2400) $PN AA70
J 2
(-5035 2410);
DISPLAY 0.617021 (-5035 2410);
PAINT ORANGE (-5035 2410);
FORCEPROP 2 LASTPIN (-5025 2350) $PN W72
J 2
(-5035 2360);
DISPLAY 0.617021 (-5035 2360);
PAINT ORANGE (-5035 2360);
FORCEPROP 2 LASTPIN (-5025 2300) $PN Y75
J 2
(-5035 2310);
DISPLAY 0.617021 (-5035 2310);
PAINT ORANGE (-5035 2310);
FORCEPROP 2 LASTPIN (-5025 2250) $PN AB77
J 2
(-5035 2260);
DISPLAY 0.617021 (-5035 2260);
PAINT ORANGE (-5035 2260);
FORCEPROP 2 LASTPIN (-5025 2200) $PN AE74
J 2
(-5035 2210);
DISPLAY 0.617021 (-5035 2210);
PAINT ORANGE (-5035 2210);
FORCEPROP 2 LASTPIN (-5025 2150) $PN AF75
J 2
(-5035 2160);
DISPLAY 0.617021 (-5035 2160);
PAINT ORANGE (-5035 2160);
FORCEPROP 2 LASTPIN (-5025 2100) $PN W76
J 2
(-5035 2110);
DISPLAY 0.617021 (-5035 2110);
PAINT ORANGE (-5035 2110);
FORCEPROP 2 LASTPIN (-5025 2050) $PN Y77
J 2
(-5035 2060);
DISPLAY 0.617021 (-5035 2060);
PAINT ORANGE (-5035 2060);
FORCEPROP 2 LASTPIN (-5025 2000) $PN AC74
J 2
(-5035 2010);
DISPLAY 0.617021 (-5035 2010);
PAINT ORANGE (-5035 2010);
FORCEPROP 2 LASTPIN (-5025 1950) $PN AE76
J 2
(-5035 1960);
DISPLAY 0.617021 (-5035 1960);
PAINT ORANGE (-5035 1960);
FORCEPROP 2 LASTPIN (-5025 1900) $PN AK75
J 2
(-5035 1910);
DISPLAY 0.617021 (-5035 1910);
PAINT ORANGE (-5035 1910);
FORCEPROP 2 LASTPIN (-5025 1850) $PN AM77
J 2
(-5035 1860);
DISPLAY 0.617021 (-5035 1860);
PAINT ORANGE (-5035 1860);
FORCEPROP 2 LASTPIN (-5025 1800) $PN AR74
J 2
(-5035 1810);
DISPLAY 0.617021 (-5035 1810);
PAINT ORANGE (-5035 1810);
FORCEPROP 2 LASTPIN (-5025 1750) $PN AT75
J 2
(-5035 1760);
DISPLAY 0.617021 (-5035 1760);
PAINT ORANGE (-5035 1760);
FORCEPROP 2 LASTPIN (-5025 1700) $PN AJ76
J 2
(-5035 1710);
DISPLAY 0.617021 (-5035 1710);
PAINT ORANGE (-5035 1710);
FORCEPROP 2 LASTPIN (-5025 1650) $PN AK77
J 2
(-5035 1660);
DISPLAY 0.617021 (-5035 1660);
PAINT ORANGE (-5035 1660);
FORCEPROP 2 LASTPIN (-5025 1600) $PN AN74
J 2
(-5035 1610);
DISPLAY 0.617021 (-5035 1610);
PAINT ORANGE (-5035 1610);
FORCEPROP 2 LASTPIN (-5025 1550) $PN AR76
J 2
(-5035 1560);
DISPLAY 0.617021 (-5035 1560);
PAINT ORANGE (-5035 1560);
FORCEPROP 2 LASTPIN (-3325 1350) $PN V45
J 0
(-3315 1360);
DISPLAY 0.617021 (-3315 1360);
PAINT ORANGE (-3315 1360);
FORCEPROP 2 LASTPIN (-3325 1300) $PN T45
J 0
(-3315 1310);
DISPLAY 0.617021 (-3315 1310);
PAINT ORANGE (-3315 1310);
FORCEPROP 2 LASTPIN (-3325 1250) $PN W48
J 0
(-3315 1260);
DISPLAY 0.617021 (-3315 1260);
PAINT ORANGE (-3315 1260);
FORCEPROP 2 LASTPIN (-3325 1200) $PN AB51
J 0
(-3315 1210);
DISPLAY 0.617021 (-3315 1210);
PAINT ORANGE (-3315 1210);
FORCEPROP 2 LASTPIN (-3325 1150) $PN AA46
J 0
(-3315 1160);
DISPLAY 0.617021 (-3315 1160);
PAINT ORANGE (-3315 1160);
FORCEPROP 2 LASTPIN (-3325 1100) $PN W46
J 0
(-3315 1110);
DISPLAY 0.617021 (-3315 1110);
PAINT ORANGE (-3315 1110);
FORCEPROP 2 LASTPIN (-3325 1050) $PN AB49
J 0
(-3315 1060);
DISPLAY 0.617021 (-3315 1060);
PAINT ORANGE (-3315 1060);
FORCEPROP 2 LASTPIN (-3325 1000) $PN V51
J 0
(-3315 1010);
DISPLAY 0.617021 (-3315 1010);
PAINT ORANGE (-3315 1010);
FORCEPROP 2 LASTPIN (-5025 1000) $PN V57
J 2
(-5035 1010);
DISPLAY 0.617021 (-5035 1010);
PAINT ORANGE (-5035 1010);
FORCEPROP 2 LASTPIN (-5025 950) $PN AB57
J 2
(-5035 960);
DISPLAY 0.617021 (-5035 960);
PAINT ORANGE (-5035 960);
FORCEPROP 2 LASTPIN (-5025 900) $PN V55
J 2
(-5035 910);
DISPLAY 0.617021 (-5035 910);
PAINT ORANGE (-5035 910);
FORCEPROP 2 LASTPIN (-5025 850) $PN AB55
J 2
(-5035 860);
DISPLAY 0.617021 (-5035 860);
PAINT ORANGE (-5035 860);
FORCEPROP 2 LASTPIN (-5025 800) $PN W56
J 2
(-5035 810);
DISPLAY 0.617021 (-5035 810);
PAINT ORANGE (-5035 810);
FORCEPROP 2 LASTPIN (-5025 750) $PN AA56
J 2
(-5035 760);
DISPLAY 0.617021 (-5035 760);
PAINT ORANGE (-5035 760);
FORCEPROP 2 LASTPIN (-5025 700) $PN W54
J 2
(-5035 710);
DISPLAY 0.617021 (-5035 710);
PAINT ORANGE (-5035 710);
FORCEPROP 2 LASTPIN (-5025 650) $PN AA54
J 2
(-5035 660);
DISPLAY 0.617021 (-5035 660);
PAINT ORANGE (-5035 660);
FORCEPROP 2 LASTPIN (-3325 1850) $PN AB63
J 0
(-3315 1860);
DISPLAY 0.617021 (-3315 1860);
PAINT ORANGE (-3315 1860);
FORCEPROP 2 LASTPIN (-3325 1800) $PN V63
J 0
(-3315 1810);
DISPLAY 0.617021 (-3315 1810);
PAINT ORANGE (-3315 1810);
FORCEPROP 2 LASTPIN (-3325 1750) $PN AD63
J 0
(-3315 1760);
DISPLAY 0.617021 (-3315 1760);
PAINT ORANGE (-3315 1760);
FORCEPROP 2 LASTPIN (-3325 1700) $PN AA62
J 0
(-3315 1710);
DISPLAY 0.617021 (-3315 1710);
PAINT ORANGE (-3315 1710);
FORCEPROP 2 LASTPIN (-5025 550) $PN AB45
J 2
(-5035 560);
DISPLAY 0.617021 (-5035 560);
PAINT ORANGE (-5035 560);
FORCEPROP 2 LASTPIN (-3325 900) $PN AE62
J 0
(-3315 910);
DISPLAY 0.617021 (-3315 910);
PAINT ORANGE (-3315 910);
FORCEPROP 2 LASTPIN (-3325 850) $PN AA60
J 0
(-3315 860);
DISPLAY 0.617021 (-3315 860);
PAINT ORANGE (-3315 860);
FORCEPROP 2 LASTPIN (-3325 800) $PN AE56
J 0
(-3315 810);
DISPLAY 0.617021 (-3315 810);
PAINT ORANGE (-3315 810);
FORCEPROP 2 LASTPIN (-3325 750) $PN W52
J 0
(-3315 760);
DISPLAY 0.617021 (-3315 760);
PAINT ORANGE (-3315 760);
FORCEPROP 2 LASTPIN (-3325 600) $PN AD61
J 0
(-3315 610);
DISPLAY 0.617021 (-3315 610);
PAINT ORANGE (-3315 610);
FORCEPROP 2 LASTPIN (-3325 650) $PN AB61
J 0
(-3315 660);
DISPLAY 0.617021 (-3315 660);
PAINT ORANGE (-3315 660);
FORCEPROP 2 LASTPIN (-5025 2950) $PN AN68
J 2
(-5035 2960);
DISPLAY 0.617021 (-5035 2960);
PAINT ORANGE (-5035 2960);
FORCEPROP 2 LASTPIN (-5025 2900) $PN AR64
J 2
(-5035 2910);
DISPLAY 0.617021 (-5035 2910);
PAINT ORANGE (-5035 2910);
FORCEPROP 2 LASTPIN (-5025 1100) $PN AU72
J 2
(-5035 1110);
DISPLAY 0.617021 (-5035 1110);
PAINT ORANGE (-5035 1110);
FORCEPROP 1 LAST PACK_TYPE BGA1
J 0
(-4975 5000);
PAINT SKYBLUE (-4975 5000);
DISPLAY INVISIBLE (-4975 5000);
FORCEPROP 2 LAST CDS_LIB chpset_lib
J 0
(-4175 2600);
PAINT ORANGE (-4175 2600);
DISPLAY INVISIBLE (-4175 2600);
FORCEPROP 2 LAST SEC_TYPE BGA1
J 0
(-4975 5000);
DISPLAY 1.021277 (-4975 5000);
PAINT ORANGE (-4975 5000);
DISPLAY INVISIBLE (-4975 5000);
FORCEPROP 2 LAST SEC 5
J 0
(-4975 5000);
DISPLAY 0.680851 (-4975 5000);
PAINT MONO (-4975 5000);
DISPLAY INVISIBLE (-4975 5000);
FORCEPROP 2 LAST CDS_LOCATION U5D1
J 0
(-4975 4950);
DISPLAY 0.617021 (-4975 4950);
PAINT AQUA (-4975 4950);
DISPLAY INVISIBLE (-4975 4950);
FORCEPROP 1 LAST PATH I172
J 0
(-4175 4900);
PAINT GREEN (-4175 4900);
DISPLAY INVISIBLE (-4175 4900);
FORCEPROP 0 LAST ROOM CPU0
J 0
(-4975 5050);
DISPLAY 1.021277 (-4975 5050);
PAINT ORANGE (-4975 5050);
DISPLAY INVISIBLE (-4975 5050);
FORCEADD TAP..6
(-5575 1350);
FORCEPROP 3 LASTPIN (-5525 1350) SIG_NAME M_C_ECC<5>
J 0
(-5515 1360);
DISPLAY 0.659574 (-5515 1360);
PAINT MONO (-5515 1360);
DISPLAY INVISIBLE (-5515 1360);
FORCEPROP 1 LASTPIN (-5525 1350) BN 5
J 0
(-5577 1358);
DISPLAY 0.617021 (-5577 1358);
PAINT PINK (-5577 1358);
FORCEPROP 1 LAST HDL_TAP TRUE
J 0
(-5250 1225);
DISPLAY 1.595745 (-5250 1225);
PAINT GREEN (-5250 1225);
DISPLAY INVISIBLE (-5250 1225);
FORCEPROP 1 LAST BODY_TYPE PLUMBING
J 0
(-5575 1300);
DISPLAY 1.595745 (-5575 1300);
PAINT GREEN (-5575 1300);
DISPLAY INVISIBLE (-5575 1300);
FORCEPROP 2 LAST CDS_LIB mstr_standard
J 0
(-5575 1350);
PAINT MONO (-5575 1350);
DISPLAY INVISIBLE (-5575 1350);
FORCEPROP 1 LAST PATH I18
J 0
(-5577 1350);
DISPLAY 0.872340 (-5577 1350);
PAINT GREEN (-5577 1350);
DISPLAY INVISIBLE (-5577 1350);
FORCEADD TAP..6
(-5575 1400);
FORCEPROP 3 LASTPIN (-5525 1400) SIG_NAME M_C_ECC<6>
J 0
(-5515 1410);
DISPLAY 0.659574 (-5515 1410);
PAINT MONO (-5515 1410);
DISPLAY INVISIBLE (-5515 1410);
FORCEPROP 1 LASTPIN (-5525 1400) BN 6
J 0
(-5577 1408);
DISPLAY 0.617021 (-5577 1408);
PAINT PINK (-5577 1408);
FORCEPROP 1 LAST HDL_TAP TRUE
J 0
(-5250 1275);
DISPLAY 1.595745 (-5250 1275);
PAINT GREEN (-5250 1275);
DISPLAY INVISIBLE (-5250 1275);
FORCEPROP 1 LAST BODY_TYPE PLUMBING
J 0
(-5575 1350);
DISPLAY 1.595745 (-5575 1350);
PAINT GREEN (-5575 1350);
DISPLAY INVISIBLE (-5575 1350);
FORCEPROP 2 LAST CDS_LIB mstr_standard
J 0
(-5575 1400);
PAINT MONO (-5575 1400);
DISPLAY INVISIBLE (-5575 1400);
FORCEPROP 1 LAST PATH I19
J 0
(-5577 1400);
DISPLAY 0.872340 (-5577 1400);
PAINT GREEN (-5577 1400);
DISPLAY INVISIBLE (-5577 1400);
FORCEADD OFFPAGE..5
(-6425 850);
FORCEPROP 2 LAST $XR1 48 
J 0
(-6769 850);
DISPLAY 0.638298 (-6769 850);
PAINT MONO (-6769 850);
FORCEPROP 2 LAST $XR0 47 
J 0
(-6679 850);
DISPLAY 0.638298 (-6679 850);
PAINT MONO (-6679 850);
FORCEPROP 1 LAST COMMENT_BODY TRUE
J 0
(-6325 775);
DISPLAY 1.170213 (-6325 775);
PAINT GREEN (-6325 775);
DISPLAY INVISIBLE (-6325 775);
FORCEPROP 1 LAST OFFPAGE TRUE
J 0
(-6100 725);
DISPLAY 1.170213 (-6100 725);
PAINT GREEN (-6100 725);
DISPLAY INVISIBLE (-6100 725);
FORCEPROP 2 LAST CDS_LIB mstr_standard
J 0
(-6425 850);
PAINT MONO (-6425 850);
DISPLAY INVISIBLE (-6425 850);
FORCEPROP 2 LAST PATH I2
J 0
(-6375 925);
DISPLAY 1.021277 (-6375 925);
PAINT ORANGE (-6375 925);
DISPLAY INVISIBLE (-6375 925);
FORCEADD TAP..6
(-5575 1450);
FORCEPROP 3 LASTPIN (-5525 1450) SIG_NAME M_C_ECC<7>
J 0
(-5515 1460);
DISPLAY 0.659574 (-5515 1460);
PAINT MONO (-5515 1460);
DISPLAY INVISIBLE (-5515 1460);
FORCEPROP 1 LASTPIN (-5525 1450) BN 7
J 0
(-5577 1458);
DISPLAY 0.617021 (-5577 1458);
PAINT PINK (-5577 1458);
FORCEPROP 1 LAST HDL_TAP TRUE
J 0
(-5250 1325);
DISPLAY 1.595745 (-5250 1325);
PAINT GREEN (-5250 1325);
DISPLAY INVISIBLE (-5250 1325);
FORCEPROP 1 LAST BODY_TYPE PLUMBING
J 0
(-5575 1400);
DISPLAY 1.595745 (-5575 1400);
PAINT GREEN (-5575 1400);
DISPLAY INVISIBLE (-5575 1400);
FORCEPROP 2 LAST CDS_LIB mstr_standard
J 0
(-5575 1450);
PAINT MONO (-5575 1450);
DISPLAY INVISIBLE (-5575 1450);
FORCEPROP 1 LAST PATH I20
J 0
(-5577 1450);
DISPLAY 0.872340 (-5577 1450);
PAINT GREEN (-5577 1450);
DISPLAY INVISIBLE (-5577 1450);
FORCEADD TAP..6
(-5575 1600);
FORCEPROP 3 LASTPIN (-5525 1600) SIG_NAME M_C_DQ<1>
J 0
(-5515 1610);
DISPLAY 0.659574 (-5515 1610);
PAINT MONO (-5515 1610);
DISPLAY INVISIBLE (-5515 1610);
FORCEPROP 1 LASTPIN (-5525 1600) BN 1
J 0
(-5577 1608);
DISPLAY 0.617021 (-5577 1608);
PAINT PINK (-5577 1608);
FORCEPROP 1 LAST HDL_TAP TRUE
J 0
(-5250 1475);
DISPLAY 1.595745 (-5250 1475);
PAINT GREEN (-5250 1475);
DISPLAY INVISIBLE (-5250 1475);
FORCEPROP 1 LAST BODY_TYPE PLUMBING
J 0
(-5575 1550);
DISPLAY 1.595745 (-5575 1550);
PAINT GREEN (-5575 1550);
DISPLAY INVISIBLE (-5575 1550);
FORCEPROP 2 LAST CDS_LIB mstr_standard
J 0
(-5575 1600);
PAINT MONO (-5575 1600);
DISPLAY INVISIBLE (-5575 1600);
FORCEPROP 1 LAST PATH I21
J 0
(-5577 1600);
DISPLAY 0.872340 (-5577 1600);
PAINT GREEN (-5577 1600);
DISPLAY INVISIBLE (-5577 1600);
FORCEADD TAP..6
(-5575 1550);
FORCEPROP 3 LASTPIN (-5525 1550) SIG_NAME M_C_DQ<0>
J 0
(-5515 1560);
DISPLAY 0.659574 (-5515 1560);
PAINT MONO (-5515 1560);
DISPLAY INVISIBLE (-5515 1560);
FORCEPROP 1 LASTPIN (-5525 1550) BN 0
J 0
(-5577 1558);
DISPLAY 0.617021 (-5577 1558);
PAINT PINK (-5577 1558);
FORCEPROP 1 LAST HDL_TAP TRUE
J 0
(-5250 1425);
DISPLAY 1.595745 (-5250 1425);
PAINT GREEN (-5250 1425);
DISPLAY INVISIBLE (-5250 1425);
FORCEPROP 1 LAST BODY_TYPE PLUMBING
J 0
(-5575 1500);
DISPLAY 1.595745 (-5575 1500);
PAINT GREEN (-5575 1500);
DISPLAY INVISIBLE (-5575 1500);
FORCEPROP 2 LAST CDS_LIB mstr_standard
J 0
(-5575 1550);
PAINT MONO (-5575 1550);
DISPLAY INVISIBLE (-5575 1550);
FORCEPROP 1 LAST PATH I22
J 0
(-5577 1550);
DISPLAY 0.872340 (-5577 1550);
PAINT GREEN (-5577 1550);
DISPLAY INVISIBLE (-5577 1550);
FORCEADD TAP..6
(-5575 1650);
FORCEPROP 3 LASTPIN (-5525 1650) SIG_NAME M_C_DQ<2>
J 0
(-5515 1660);
DISPLAY 0.659574 (-5515 1660);
PAINT MONO (-5515 1660);
DISPLAY INVISIBLE (-5515 1660);
FORCEPROP 1 LASTPIN (-5525 1650) BN 2
J 0
(-5577 1658);
DISPLAY 0.617021 (-5577 1658);
PAINT PINK (-5577 1658);
FORCEPROP 1 LAST HDL_TAP TRUE
J 0
(-5250 1525);
DISPLAY 1.595745 (-5250 1525);
PAINT GREEN (-5250 1525);
DISPLAY INVISIBLE (-5250 1525);
FORCEPROP 1 LAST BODY_TYPE PLUMBING
J 0
(-5575 1600);
DISPLAY 1.595745 (-5575 1600);
PAINT GREEN (-5575 1600);
DISPLAY INVISIBLE (-5575 1600);
FORCEPROP 2 LAST CDS_LIB mstr_standard
J 0
(-5575 1650);
PAINT MONO (-5575 1650);
DISPLAY INVISIBLE (-5575 1650);
FORCEPROP 1 LAST PATH I23
J 0
(-5577 1650);
DISPLAY 0.872340 (-5577 1650);
PAINT GREEN (-5577 1650);
DISPLAY INVISIBLE (-5577 1650);
FORCEADD TAP..6
(-5575 1700);
FORCEPROP 3 LASTPIN (-5525 1700) SIG_NAME M_C_DQ<3>
J 0
(-5515 1710);
DISPLAY 0.659574 (-5515 1710);
PAINT MONO (-5515 1710);
DISPLAY INVISIBLE (-5515 1710);
FORCEPROP 1 LASTPIN (-5525 1700) BN 3
J 0
(-5577 1708);
DISPLAY 0.617021 (-5577 1708);
PAINT PINK (-5577 1708);
FORCEPROP 1 LAST HDL_TAP TRUE
J 0
(-5250 1575);
DISPLAY 1.595745 (-5250 1575);
PAINT GREEN (-5250 1575);
DISPLAY INVISIBLE (-5250 1575);
FORCEPROP 1 LAST BODY_TYPE PLUMBING
J 0
(-5575 1650);
DISPLAY 1.595745 (-5575 1650);
PAINT GREEN (-5575 1650);
DISPLAY INVISIBLE (-5575 1650);
FORCEPROP 2 LAST CDS_LIB mstr_standard
J 0
(-5575 1700);
PAINT MONO (-5575 1700);
DISPLAY INVISIBLE (-5575 1700);
FORCEPROP 1 LAST PATH I24
J 0
(-5577 1700);
DISPLAY 0.872340 (-5577 1700);
PAINT GREEN (-5577 1700);
DISPLAY INVISIBLE (-5577 1700);
FORCEADD TAP..6
(-5575 1750);
FORCEPROP 3 LASTPIN (-5525 1750) SIG_NAME M_C_DQ<4>
J 0
(-5515 1760);
DISPLAY 0.659574 (-5515 1760);
PAINT MONO (-5515 1760);
DISPLAY INVISIBLE (-5515 1760);
FORCEPROP 1 LASTPIN (-5525 1750) BN 4
J 0
(-5577 1758);
DISPLAY 0.617021 (-5577 1758);
PAINT PINK (-5577 1758);
FORCEPROP 1 LAST HDL_TAP TRUE
J 0
(-5250 1625);
DISPLAY 1.595745 (-5250 1625);
PAINT GREEN (-5250 1625);
DISPLAY INVISIBLE (-5250 1625);
FORCEPROP 1 LAST BODY_TYPE PLUMBING
J 0
(-5575 1700);
DISPLAY 1.595745 (-5575 1700);
PAINT GREEN (-5575 1700);
DISPLAY INVISIBLE (-5575 1700);
FORCEPROP 2 LAST CDS_LIB mstr_standard
J 0
(-5575 1750);
PAINT MONO (-5575 1750);
DISPLAY INVISIBLE (-5575 1750);
FORCEPROP 1 LAST PATH I25
J 0
(-5577 1750);
DISPLAY 0.872340 (-5577 1750);
PAINT GREEN (-5577 1750);
DISPLAY INVISIBLE (-5577 1750);
FORCEADD TAP..6
(-5575 1800);
FORCEPROP 3 LASTPIN (-5525 1800) SIG_NAME M_C_DQ<5>
J 0
(-5515 1810);
DISPLAY 0.659574 (-5515 1810);
PAINT MONO (-5515 1810);
DISPLAY INVISIBLE (-5515 1810);
FORCEPROP 1 LASTPIN (-5525 1800) BN 5
J 0
(-5577 1808);
DISPLAY 0.617021 (-5577 1808);
PAINT PINK (-5577 1808);
FORCEPROP 1 LAST HDL_TAP TRUE
J 0
(-5250 1675);
DISPLAY 1.595745 (-5250 1675);
PAINT GREEN (-5250 1675);
DISPLAY INVISIBLE (-5250 1675);
FORCEPROP 1 LAST BODY_TYPE PLUMBING
J 0
(-5575 1750);
DISPLAY 1.595745 (-5575 1750);
PAINT GREEN (-5575 1750);
DISPLAY INVISIBLE (-5575 1750);
FORCEPROP 2 LAST CDS_LIB mstr_standard
J 0
(-5575 1800);
PAINT MONO (-5575 1800);
DISPLAY INVISIBLE (-5575 1800);
FORCEPROP 1 LAST PATH I26
J 0
(-5577 1800);
DISPLAY 0.872340 (-5577 1800);
PAINT GREEN (-5577 1800);
DISPLAY INVISIBLE (-5577 1800);
FORCEADD TAP..6
(-5575 1850);
FORCEPROP 3 LASTPIN (-5525 1850) SIG_NAME M_C_DQ<6>
J 0
(-5515 1860);
DISPLAY 0.659574 (-5515 1860);
PAINT MONO (-5515 1860);
DISPLAY INVISIBLE (-5515 1860);
FORCEPROP 1 LASTPIN (-5525 1850) BN 6
J 0
(-5577 1858);
DISPLAY 0.617021 (-5577 1858);
PAINT PINK (-5577 1858);
FORCEPROP 1 LAST HDL_TAP TRUE
J 0
(-5250 1725);
DISPLAY 1.595745 (-5250 1725);
PAINT GREEN (-5250 1725);
DISPLAY INVISIBLE (-5250 1725);
FORCEPROP 1 LAST BODY_TYPE PLUMBING
J 0
(-5575 1800);
DISPLAY 1.595745 (-5575 1800);
PAINT GREEN (-5575 1800);
DISPLAY INVISIBLE (-5575 1800);
FORCEPROP 2 LAST CDS_LIB mstr_standard
J 0
(-5575 1850);
PAINT MONO (-5575 1850);
DISPLAY INVISIBLE (-5575 1850);
FORCEPROP 1 LAST PATH I27
J 0
(-5577 1850);
DISPLAY 0.872340 (-5577 1850);
PAINT GREEN (-5577 1850);
DISPLAY INVISIBLE (-5577 1850);
FORCEADD TAP..6
(-5575 1900);
FORCEPROP 3 LASTPIN (-5525 1900) SIG_NAME M_C_DQ<7>
J 0
(-5515 1910);
DISPLAY 0.659574 (-5515 1910);
PAINT MONO (-5515 1910);
DISPLAY INVISIBLE (-5515 1910);
FORCEPROP 1 LASTPIN (-5525 1900) BN 7
J 0
(-5577 1908);
DISPLAY 0.617021 (-5577 1908);
PAINT PINK (-5577 1908);
FORCEPROP 1 LAST HDL_TAP TRUE
J 0
(-5250 1775);
DISPLAY 1.595745 (-5250 1775);
PAINT GREEN (-5250 1775);
DISPLAY INVISIBLE (-5250 1775);
FORCEPROP 1 LAST BODY_TYPE PLUMBING
J 0
(-5575 1850);
DISPLAY 1.595745 (-5575 1850);
PAINT GREEN (-5575 1850);
DISPLAY INVISIBLE (-5575 1850);
FORCEPROP 2 LAST CDS_LIB mstr_standard
J 0
(-5575 1900);
PAINT MONO (-5575 1900);
DISPLAY INVISIBLE (-5575 1900);
FORCEPROP 1 LAST PATH I28
J 0
(-5577 1900);
DISPLAY 0.872340 (-5577 1900);
PAINT GREEN (-5577 1900);
DISPLAY INVISIBLE (-5577 1900);
FORCEADD TAP..6
(-5575 1950);
FORCEPROP 3 LASTPIN (-5525 1950) SIG_NAME M_C_DQ<8>
J 0
(-5515 1960);
DISPLAY 0.659574 (-5515 1960);
PAINT MONO (-5515 1960);
DISPLAY INVISIBLE (-5515 1960);
FORCEPROP 1 LASTPIN (-5525 1950) BN 8
J 0
(-5577 1958);
DISPLAY 0.617021 (-5577 1958);
PAINT PINK (-5577 1958);
FORCEPROP 1 LAST HDL_TAP TRUE
J 0
(-5250 1825);
DISPLAY 1.595745 (-5250 1825);
PAINT GREEN (-5250 1825);
DISPLAY INVISIBLE (-5250 1825);
FORCEPROP 1 LAST BODY_TYPE PLUMBING
J 0
(-5575 1900);
DISPLAY 1.595745 (-5575 1900);
PAINT GREEN (-5575 1900);
DISPLAY INVISIBLE (-5575 1900);
FORCEPROP 2 LAST CDS_LIB mstr_standard
J 0
(-5575 1950);
PAINT MONO (-5575 1950);
DISPLAY INVISIBLE (-5575 1950);
FORCEPROP 1 LAST PATH I29
J 0
(-5577 1950);
DISPLAY 0.872340 (-5577 1950);
PAINT GREEN (-5577 1950);
DISPLAY INVISIBLE (-5577 1950);
FORCEADD OFFPAGE..5
(-6425 1050);
FORCEPROP 2 LAST $XR1 48 
J 0
(-6769 1050);
DISPLAY 0.638298 (-6769 1050);
PAINT MONO (-6769 1050);
FORCEPROP 2 LAST $XR0 47 
J 0
(-6679 1050);
DISPLAY 0.638298 (-6679 1050);
PAINT MONO (-6679 1050);
FORCEPROP 1 LAST COMMENT_BODY TRUE
J 0
(-6325 975);
DISPLAY 1.170213 (-6325 975);
PAINT GREEN (-6325 975);
DISPLAY INVISIBLE (-6325 975);
FORCEPROP 1 LAST OFFPAGE TRUE
J 0
(-6100 925);
DISPLAY 1.170213 (-6100 925);
PAINT GREEN (-6100 925);
DISPLAY INVISIBLE (-6100 925);
FORCEPROP 2 LAST CDS_LIB mstr_standard
J 0
(-6425 1050);
PAINT MONO (-6425 1050);
DISPLAY INVISIBLE (-6425 1050);
FORCEPROP 2 LAST PATH I3
J 0
(-6375 1125);
DISPLAY 1.021277 (-6375 1125);
PAINT ORANGE (-6375 1125);
DISPLAY INVISIBLE (-6375 1125);
FORCEADD TAP..6
(-5575 2100);
FORCEPROP 3 LASTPIN (-5525 2100) SIG_NAME M_C_DQ<11>
J 0
(-5515 2110);
DISPLAY 0.659574 (-5515 2110);
PAINT MONO (-5515 2110);
DISPLAY INVISIBLE (-5515 2110);
FORCEPROP 1 LASTPIN (-5525 2100) BN 11
J 0
(-5577 2108);
DISPLAY 0.617021 (-5577 2108);
PAINT PINK (-5577 2108);
FORCEPROP 1 LAST HDL_TAP TRUE
J 0
(-5250 1975);
DISPLAY 1.595745 (-5250 1975);
PAINT GREEN (-5250 1975);
DISPLAY INVISIBLE (-5250 1975);
FORCEPROP 1 LAST BODY_TYPE PLUMBING
J 0
(-5575 2050);
DISPLAY 1.595745 (-5575 2050);
PAINT GREEN (-5575 2050);
DISPLAY INVISIBLE (-5575 2050);
FORCEPROP 2 LAST CDS_LIB mstr_standard
J 0
(-5575 2100);
PAINT MONO (-5575 2100);
DISPLAY INVISIBLE (-5575 2100);
FORCEPROP 1 LAST PATH I31
J 0
(-5577 2100);
DISPLAY 0.872340 (-5577 2100);
PAINT GREEN (-5577 2100);
DISPLAY INVISIBLE (-5577 2100);
FORCEADD TAP..6
(-5575 2050);
FORCEPROP 3 LASTPIN (-5525 2050) SIG_NAME M_C_DQ<10>
J 0
(-5515 2060);
DISPLAY 0.659574 (-5515 2060);
PAINT MONO (-5515 2060);
DISPLAY INVISIBLE (-5515 2060);
FORCEPROP 1 LASTPIN (-5525 2050) BN 10
J 0
(-5577 2058);
DISPLAY 0.617021 (-5577 2058);
PAINT PINK (-5577 2058);
FORCEPROP 1 LAST HDL_TAP TRUE
J 0
(-5250 1925);
DISPLAY 1.595745 (-5250 1925);
PAINT GREEN (-5250 1925);
DISPLAY INVISIBLE (-5250 1925);
FORCEPROP 1 LAST BODY_TYPE PLUMBING
J 0
(-5575 2000);
DISPLAY 1.595745 (-5575 2000);
PAINT GREEN (-5575 2000);
DISPLAY INVISIBLE (-5575 2000);
FORCEPROP 2 LAST CDS_LIB mstr_standard
J 0
(-5575 2050);
PAINT MONO (-5575 2050);
DISPLAY INVISIBLE (-5575 2050);
FORCEPROP 1 LAST PATH I32
J 0
(-5577 2050);
DISPLAY 0.872340 (-5577 2050);
PAINT GREEN (-5577 2050);
DISPLAY INVISIBLE (-5577 2050);
FORCEADD TAP..6
(-5575 2000);
FORCEPROP 3 LASTPIN (-5525 2000) SIG_NAME M_C_DQ<9>
J 0
(-5515 2010);
DISPLAY 0.659574 (-5515 2010);
PAINT MONO (-5515 2010);
DISPLAY INVISIBLE (-5515 2010);
FORCEPROP 1 LASTPIN (-5525 2000) BN 9
J 0
(-5577 2008);
DISPLAY 0.617021 (-5577 2008);
PAINT PINK (-5577 2008);
FORCEPROP 1 LAST HDL_TAP TRUE
J 0
(-5250 1875);
DISPLAY 1.595745 (-5250 1875);
PAINT GREEN (-5250 1875);
DISPLAY INVISIBLE (-5250 1875);
FORCEPROP 1 LAST BODY_TYPE PLUMBING
J 0
(-5575 1950);
DISPLAY 1.595745 (-5575 1950);
PAINT GREEN (-5575 1950);
DISPLAY INVISIBLE (-5575 1950);
FORCEPROP 2 LAST CDS_LIB mstr_standard
J 0
(-5575 2000);
PAINT MONO (-5575 2000);
DISPLAY INVISIBLE (-5575 2000);
FORCEPROP 1 LAST PATH I33
J 0
(-5577 2000);
DISPLAY 0.872340 (-5577 2000);
PAINT GREEN (-5577 2000);
DISPLAY INVISIBLE (-5577 2000);
FORCEADD TAP..6
(-5575 2150);
FORCEPROP 3 LASTPIN (-5525 2150) SIG_NAME M_C_DQ<12>
J 0
(-5515 2160);
DISPLAY 0.659574 (-5515 2160);
PAINT MONO (-5515 2160);
DISPLAY INVISIBLE (-5515 2160);
FORCEPROP 1 LASTPIN (-5525 2150) BN 12
J 0
(-5577 2158);
DISPLAY 0.617021 (-5577 2158);
PAINT PINK (-5577 2158);
FORCEPROP 1 LAST HDL_TAP TRUE
J 0
(-5250 2025);
DISPLAY 1.595745 (-5250 2025);
PAINT GREEN (-5250 2025);
DISPLAY INVISIBLE (-5250 2025);
FORCEPROP 1 LAST BODY_TYPE PLUMBING
J 0
(-5575 2100);
DISPLAY 1.595745 (-5575 2100);
PAINT GREEN (-5575 2100);
DISPLAY INVISIBLE (-5575 2100);
FORCEPROP 2 LAST CDS_LIB mstr_standard
J 0
(-5575 2150);
PAINT MONO (-5575 2150);
DISPLAY INVISIBLE (-5575 2150);
FORCEPROP 1 LAST PATH I34
J 0
(-5577 2150);
DISPLAY 0.872340 (-5577 2150);
PAINT GREEN (-5577 2150);
DISPLAY INVISIBLE (-5577 2150);
FORCEADD TAP..6
(-5575 2200);
FORCEPROP 3 LASTPIN (-5525 2200) SIG_NAME M_C_DQ<13>
J 0
(-5515 2210);
DISPLAY 0.659574 (-5515 2210);
PAINT MONO (-5515 2210);
DISPLAY INVISIBLE (-5515 2210);
FORCEPROP 1 LASTPIN (-5525 2200) BN 13
J 0
(-5577 2208);
DISPLAY 0.617021 (-5577 2208);
PAINT PINK (-5577 2208);
FORCEPROP 1 LAST HDL_TAP TRUE
J 0
(-5250 2075);
DISPLAY 1.595745 (-5250 2075);
PAINT GREEN (-5250 2075);
DISPLAY INVISIBLE (-5250 2075);
FORCEPROP 1 LAST BODY_TYPE PLUMBING
J 0
(-5575 2150);
DISPLAY 1.595745 (-5575 2150);
PAINT GREEN (-5575 2150);
DISPLAY INVISIBLE (-5575 2150);
FORCEPROP 2 LAST CDS_LIB mstr_standard
J 0
(-5575 2200);
PAINT MONO (-5575 2200);
DISPLAY INVISIBLE (-5575 2200);
FORCEPROP 1 LAST PATH I35
J 0
(-5577 2200);
DISPLAY 0.872340 (-5577 2200);
PAINT GREEN (-5577 2200);
DISPLAY INVISIBLE (-5577 2200);
FORCEADD TAP..6
(-5575 2250);
FORCEPROP 3 LASTPIN (-5525 2250) SIG_NAME M_C_DQ<14>
J 0
(-5515 2260);
DISPLAY 0.659574 (-5515 2260);
PAINT MONO (-5515 2260);
DISPLAY INVISIBLE (-5515 2260);
FORCEPROP 1 LASTPIN (-5525 2250) BN 14
J 0
(-5577 2258);
DISPLAY 0.617021 (-5577 2258);
PAINT PINK (-5577 2258);
FORCEPROP 1 LAST HDL_TAP TRUE
J 0
(-5250 2125);
DISPLAY 1.595745 (-5250 2125);
PAINT GREEN (-5250 2125);
DISPLAY INVISIBLE (-5250 2125);
FORCEPROP 1 LAST BODY_TYPE PLUMBING
J 0
(-5575 2200);
DISPLAY 1.595745 (-5575 2200);
PAINT GREEN (-5575 2200);
DISPLAY INVISIBLE (-5575 2200);
FORCEPROP 2 LAST CDS_LIB mstr_standard
J 0
(-5575 2250);
PAINT MONO (-5575 2250);
DISPLAY INVISIBLE (-5575 2250);
FORCEPROP 1 LAST PATH I36
J 0
(-5577 2250);
DISPLAY 0.872340 (-5577 2250);
PAINT GREEN (-5577 2250);
DISPLAY INVISIBLE (-5577 2250);
FORCEADD TAP..6
(-5575 2300);
FORCEPROP 3 LASTPIN (-5525 2300) SIG_NAME M_C_DQ<15>
J 0
(-5515 2310);
DISPLAY 0.659574 (-5515 2310);
PAINT MONO (-5515 2310);
DISPLAY INVISIBLE (-5515 2310);
FORCEPROP 1 LASTPIN (-5525 2300) BN 15
J 0
(-5577 2308);
DISPLAY 0.617021 (-5577 2308);
PAINT PINK (-5577 2308);
FORCEPROP 1 LAST HDL_TAP TRUE
J 0
(-5250 2175);
DISPLAY 1.595745 (-5250 2175);
PAINT GREEN (-5250 2175);
DISPLAY INVISIBLE (-5250 2175);
FORCEPROP 1 LAST BODY_TYPE PLUMBING
J 0
(-5575 2250);
DISPLAY 1.595745 (-5575 2250);
PAINT GREEN (-5575 2250);
DISPLAY INVISIBLE (-5575 2250);
FORCEPROP 2 LAST CDS_LIB mstr_standard
J 0
(-5575 2300);
PAINT MONO (-5575 2300);
DISPLAY INVISIBLE (-5575 2300);
FORCEPROP 1 LAST PATH I37
J 0
(-5577 2300);
DISPLAY 0.872340 (-5577 2300);
PAINT GREEN (-5577 2300);
DISPLAY INVISIBLE (-5577 2300);
FORCEADD TAP..6
(-5575 2350);
FORCEPROP 3 LASTPIN (-5525 2350) SIG_NAME M_C_DQ<16>
J 0
(-5515 2360);
DISPLAY 0.659574 (-5515 2360);
PAINT MONO (-5515 2360);
DISPLAY INVISIBLE (-5515 2360);
FORCEPROP 1 LASTPIN (-5525 2350) BN 16
J 0
(-5577 2358);
DISPLAY 0.617021 (-5577 2358);
PAINT PINK (-5577 2358);
FORCEPROP 1 LAST HDL_TAP TRUE
J 0
(-5250 2225);
DISPLAY 1.595745 (-5250 2225);
PAINT GREEN (-5250 2225);
DISPLAY INVISIBLE (-5250 2225);
FORCEPROP 1 LAST BODY_TYPE PLUMBING
J 0
(-5575 2300);
DISPLAY 1.595745 (-5575 2300);
PAINT GREEN (-5575 2300);
DISPLAY INVISIBLE (-5575 2300);
FORCEPROP 2 LAST CDS_LIB mstr_standard
J 0
(-5575 2350);
PAINT MONO (-5575 2350);
DISPLAY INVISIBLE (-5575 2350);
FORCEPROP 1 LAST PATH I38
J 0
(-5577 2350);
DISPLAY 0.872340 (-5577 2350);
PAINT GREEN (-5577 2350);
DISPLAY INVISIBLE (-5577 2350);
FORCEADD TAP..6
(-5575 2400);
FORCEPROP 3 LASTPIN (-5525 2400) SIG_NAME M_C_DQ<17>
J 0
(-5515 2410);
DISPLAY 0.659574 (-5515 2410);
PAINT MONO (-5515 2410);
DISPLAY INVISIBLE (-5515 2410);
FORCEPROP 1 LASTPIN (-5525 2400) BN 17
J 0
(-5577 2408);
DISPLAY 0.617021 (-5577 2408);
PAINT PINK (-5577 2408);
FORCEPROP 1 LAST HDL_TAP TRUE
J 0
(-5250 2275);
DISPLAY 1.595745 (-5250 2275);
PAINT GREEN (-5250 2275);
DISPLAY INVISIBLE (-5250 2275);
FORCEPROP 1 LAST BODY_TYPE PLUMBING
J 0
(-5575 2350);
DISPLAY 1.595745 (-5575 2350);
PAINT GREEN (-5575 2350);
DISPLAY INVISIBLE (-5575 2350);
FORCEPROP 2 LAST CDS_LIB mstr_standard
J 0
(-5575 2400);
PAINT MONO (-5575 2400);
DISPLAY INVISIBLE (-5575 2400);
FORCEPROP 1 LAST PATH I39
J 0
(-5577 2400);
DISPLAY 0.872340 (-5577 2400);
PAINT GREEN (-5577 2400);
DISPLAY INVISIBLE (-5577 2400);
FORCEADD OFFPAGE..6
(-6425 1500);
FORCEPROP 2 LAST $XR1 48 
J 0
(-6764 1500);
DISPLAY 0.638298 (-6764 1500);
PAINT MONO (-6764 1500);
FORCEPROP 2 LAST $XR0 47 
J 0
(-6674 1500);
DISPLAY 0.638298 (-6674 1500);
PAINT MONO (-6674 1500);
FORCEPROP 1 LAST COMMENT_BODY TRUE
J 0
(-6325 1425);
DISPLAY 1.170213 (-6325 1425);
PAINT GREEN (-6325 1425);
DISPLAY INVISIBLE (-6325 1425);
FORCEPROP 1 LAST OFFPAGE TRUE
J 0
(-6100 1375);
DISPLAY 1.170213 (-6100 1375);
PAINT GREEN (-6100 1375);
DISPLAY INVISIBLE (-6100 1375);
FORCEPROP 2 LAST CDS_LIB mstr_standard
J 0
(-6425 1500);
PAINT MONO (-6425 1500);
DISPLAY INVISIBLE (-6425 1500);
FORCEPROP 2 LAST PATH I4
J 0
(-6375 1575);
DISPLAY 1.021277 (-6375 1575);
PAINT ORANGE (-6375 1575);
DISPLAY INVISIBLE (-6375 1575);
FORCEADD TAP..6
(-5575 2450);
FORCEPROP 3 LASTPIN (-5525 2450) SIG_NAME M_C_DQ<18>
J 0
(-5515 2460);
DISPLAY 0.659574 (-5515 2460);
PAINT MONO (-5515 2460);
DISPLAY INVISIBLE (-5515 2460);
FORCEPROP 1 LASTPIN (-5525 2450) BN 18
J 0
(-5577 2458);
DISPLAY 0.617021 (-5577 2458);
PAINT PINK (-5577 2458);
FORCEPROP 1 LAST HDL_TAP TRUE
J 0
(-5250 2325);
DISPLAY 1.595745 (-5250 2325);
PAINT GREEN (-5250 2325);
DISPLAY INVISIBLE (-5250 2325);
FORCEPROP 1 LAST BODY_TYPE PLUMBING
J 0
(-5575 2400);
DISPLAY 1.595745 (-5575 2400);
PAINT GREEN (-5575 2400);
DISPLAY INVISIBLE (-5575 2400);
FORCEPROP 2 LAST CDS_LIB mstr_standard
J 0
(-5575 2450);
PAINT MONO (-5575 2450);
DISPLAY INVISIBLE (-5575 2450);
FORCEPROP 1 LAST PATH I40
J 0
(-5577 2450);
DISPLAY 0.872340 (-5577 2450);
PAINT GREEN (-5577 2450);
DISPLAY INVISIBLE (-5577 2450);
FORCEADD TAP..6
(-5575 2500);
FORCEPROP 3 LASTPIN (-5525 2500) SIG_NAME M_C_DQ<19>
J 0
(-5515 2510);
DISPLAY 0.659574 (-5515 2510);
PAINT MONO (-5515 2510);
DISPLAY INVISIBLE (-5515 2510);
FORCEPROP 1 LASTPIN (-5525 2500) BN 19
J 0
(-5577 2508);
DISPLAY 0.617021 (-5577 2508);
PAINT PINK (-5577 2508);
FORCEPROP 1 LAST HDL_TAP TRUE
J 0
(-5250 2375);
DISPLAY 1.595745 (-5250 2375);
PAINT GREEN (-5250 2375);
DISPLAY INVISIBLE (-5250 2375);
FORCEPROP 1 LAST BODY_TYPE PLUMBING
J 0
(-5575 2450);
DISPLAY 1.595745 (-5575 2450);
PAINT GREEN (-5575 2450);
DISPLAY INVISIBLE (-5575 2450);
FORCEPROP 2 LAST CDS_LIB mstr_standard
J 0
(-5575 2500);
PAINT MONO (-5575 2500);
DISPLAY INVISIBLE (-5575 2500);
FORCEPROP 1 LAST PATH I41
J 0
(-5577 2500);
DISPLAY 0.872340 (-5577 2500);
PAINT GREEN (-5577 2500);
DISPLAY INVISIBLE (-5577 2500);
FORCEADD TAP..6
(-5575 2600);
FORCEPROP 3 LASTPIN (-5525 2600) SIG_NAME M_C_DQ<21>
J 0
(-5515 2610);
DISPLAY 0.659574 (-5515 2610);
PAINT MONO (-5515 2610);
DISPLAY INVISIBLE (-5515 2610);
FORCEPROP 1 LASTPIN (-5525 2600) BN 21
J 0
(-5577 2608);
DISPLAY 0.617021 (-5577 2608);
PAINT PINK (-5577 2608);
FORCEPROP 1 LAST HDL_TAP TRUE
J 0
(-5250 2475);
DISPLAY 1.595745 (-5250 2475);
PAINT GREEN (-5250 2475);
DISPLAY INVISIBLE (-5250 2475);
FORCEPROP 1 LAST BODY_TYPE PLUMBING
J 0
(-5575 2550);
DISPLAY 1.595745 (-5575 2550);
PAINT GREEN (-5575 2550);
DISPLAY INVISIBLE (-5575 2550);
FORCEPROP 2 LAST CDS_LIB mstr_standard
J 0
(-5575 2600);
PAINT MONO (-5575 2600);
DISPLAY INVISIBLE (-5575 2600);
FORCEPROP 1 LAST PATH I42
J 0
(-5577 2600);
DISPLAY 0.872340 (-5577 2600);
PAINT GREEN (-5577 2600);
DISPLAY INVISIBLE (-5577 2600);
FORCEADD TAP..6
(-5575 2550);
FORCEPROP 3 LASTPIN (-5525 2550) SIG_NAME M_C_DQ<20>
J 0
(-5515 2560);
DISPLAY 0.659574 (-5515 2560);
PAINT MONO (-5515 2560);
DISPLAY INVISIBLE (-5515 2560);
FORCEPROP 1 LASTPIN (-5525 2550) BN 20
J 0
(-5577 2558);
DISPLAY 0.617021 (-5577 2558);
PAINT PINK (-5577 2558);
FORCEPROP 1 LAST HDL_TAP TRUE
J 0
(-5250 2425);
DISPLAY 1.595745 (-5250 2425);
PAINT GREEN (-5250 2425);
DISPLAY INVISIBLE (-5250 2425);
FORCEPROP 1 LAST BODY_TYPE PLUMBING
J 0
(-5575 2500);
DISPLAY 1.595745 (-5575 2500);
PAINT GREEN (-5575 2500);
DISPLAY INVISIBLE (-5575 2500);
FORCEPROP 2 LAST CDS_LIB mstr_standard
J 0
(-5575 2550);
PAINT MONO (-5575 2550);
DISPLAY INVISIBLE (-5575 2550);
FORCEPROP 1 LAST PATH I43
J 0
(-5577 2550);
DISPLAY 0.872340 (-5577 2550);
PAINT GREEN (-5577 2550);
DISPLAY INVISIBLE (-5577 2550);
FORCEADD TAP..6
(-5575 2650);
FORCEPROP 3 LASTPIN (-5525 2650) SIG_NAME M_C_DQ<22>
J 0
(-5515 2660);
DISPLAY 0.659574 (-5515 2660);
PAINT MONO (-5515 2660);
DISPLAY INVISIBLE (-5515 2660);
FORCEPROP 1 LASTPIN (-5525 2650) BN 22
J 0
(-5577 2658);
DISPLAY 0.617021 (-5577 2658);
PAINT PINK (-5577 2658);
FORCEPROP 1 LAST HDL_TAP TRUE
J 0
(-5250 2525);
DISPLAY 1.595745 (-5250 2525);
PAINT GREEN (-5250 2525);
DISPLAY INVISIBLE (-5250 2525);
FORCEPROP 1 LAST BODY_TYPE PLUMBING
J 0
(-5575 2600);
DISPLAY 1.595745 (-5575 2600);
PAINT GREEN (-5575 2600);
DISPLAY INVISIBLE (-5575 2600);
FORCEPROP 2 LAST CDS_LIB mstr_standard
J 0
(-5575 2650);
PAINT MONO (-5575 2650);
DISPLAY INVISIBLE (-5575 2650);
FORCEPROP 1 LAST PATH I44
J 0
(-5577 2650);
DISPLAY 0.872340 (-5577 2650);
PAINT GREEN (-5577 2650);
DISPLAY INVISIBLE (-5577 2650);
FORCEADD TAP..6
(-5575 2700);
FORCEPROP 3 LASTPIN (-5525 2700) SIG_NAME M_C_DQ<23>
J 0
(-5515 2710);
DISPLAY 0.659574 (-5515 2710);
PAINT MONO (-5515 2710);
DISPLAY INVISIBLE (-5515 2710);
FORCEPROP 1 LASTPIN (-5525 2700) BN 23
J 0
(-5577 2708);
DISPLAY 0.617021 (-5577 2708);
PAINT PINK (-5577 2708);
FORCEPROP 1 LAST HDL_TAP TRUE
J 0
(-5250 2575);
DISPLAY 1.595745 (-5250 2575);
PAINT GREEN (-5250 2575);
DISPLAY INVISIBLE (-5250 2575);
FORCEPROP 1 LAST BODY_TYPE PLUMBING
J 0
(-5575 2650);
DISPLAY 1.595745 (-5575 2650);
PAINT GREEN (-5575 2650);
DISPLAY INVISIBLE (-5575 2650);
FORCEPROP 2 LAST CDS_LIB mstr_standard
J 0
(-5575 2700);
PAINT MONO (-5575 2700);
DISPLAY INVISIBLE (-5575 2700);
FORCEPROP 1 LAST PATH I45
J 0
(-5577 2700);
DISPLAY 0.872340 (-5577 2700);
PAINT GREEN (-5577 2700);
DISPLAY INVISIBLE (-5577 2700);
FORCEADD TAP..6
(-5575 2750);
FORCEPROP 3 LASTPIN (-5525 2750) SIG_NAME M_C_DQ<24>
J 0
(-5515 2760);
DISPLAY 0.659574 (-5515 2760);
PAINT MONO (-5515 2760);
DISPLAY INVISIBLE (-5515 2760);
FORCEPROP 1 LASTPIN (-5525 2750) BN 24
J 0
(-5577 2758);
DISPLAY 0.617021 (-5577 2758);
PAINT PINK (-5577 2758);
FORCEPROP 1 LAST HDL_TAP TRUE
J 0
(-5250 2625);
DISPLAY 1.595745 (-5250 2625);
PAINT GREEN (-5250 2625);
DISPLAY INVISIBLE (-5250 2625);
FORCEPROP 1 LAST BODY_TYPE PLUMBING
J 0
(-5575 2700);
DISPLAY 1.595745 (-5575 2700);
PAINT GREEN (-5575 2700);
DISPLAY INVISIBLE (-5575 2700);
FORCEPROP 2 LAST CDS_LIB mstr_standard
J 0
(-5575 2750);
PAINT MONO (-5575 2750);
DISPLAY INVISIBLE (-5575 2750);
FORCEPROP 1 LAST PATH I46
J 0
(-5577 2750);
DISPLAY 0.872340 (-5577 2750);
PAINT GREEN (-5577 2750);
DISPLAY INVISIBLE (-5577 2750);
FORCEADD TAP..6
(-5575 2850);
FORCEPROP 3 LASTPIN (-5525 2850) SIG_NAME M_C_DQ<26>
J 0
(-5515 2860);
DISPLAY 0.659574 (-5515 2860);
PAINT MONO (-5515 2860);
DISPLAY INVISIBLE (-5515 2860);
FORCEPROP 1 LASTPIN (-5525 2850) BN 26
J 0
(-5577 2858);
DISPLAY 0.617021 (-5577 2858);
PAINT PINK (-5577 2858);
FORCEPROP 1 LAST HDL_TAP TRUE
J 0
(-5250 2725);
DISPLAY 1.595745 (-5250 2725);
PAINT GREEN (-5250 2725);
DISPLAY INVISIBLE (-5250 2725);
FORCEPROP 1 LAST BODY_TYPE PLUMBING
J 0
(-5575 2800);
DISPLAY 1.595745 (-5575 2800);
PAINT GREEN (-5575 2800);
DISPLAY INVISIBLE (-5575 2800);
FORCEPROP 2 LAST CDS_LIB mstr_standard
J 0
(-5575 2850);
PAINT MONO (-5575 2850);
DISPLAY INVISIBLE (-5575 2850);
FORCEPROP 1 LAST PATH I47
J 0
(-5577 2850);
DISPLAY 0.872340 (-5577 2850);
PAINT GREEN (-5577 2850);
DISPLAY INVISIBLE (-5577 2850);
FORCEADD TAP..6
(-5575 2800);
FORCEPROP 3 LASTPIN (-5525 2800) SIG_NAME M_C_DQ<25>
J 0
(-5515 2810);
DISPLAY 0.659574 (-5515 2810);
PAINT MONO (-5515 2810);
DISPLAY INVISIBLE (-5515 2810);
FORCEPROP 1 LASTPIN (-5525 2800) BN 25
J 0
(-5577 2808);
DISPLAY 0.617021 (-5577 2808);
PAINT PINK (-5577 2808);
FORCEPROP 1 LAST HDL_TAP TRUE
J 0
(-5250 2675);
DISPLAY 1.595745 (-5250 2675);
PAINT GREEN (-5250 2675);
DISPLAY INVISIBLE (-5250 2675);
FORCEPROP 1 LAST BODY_TYPE PLUMBING
J 0
(-5575 2750);
DISPLAY 1.595745 (-5575 2750);
PAINT GREEN (-5575 2750);
DISPLAY INVISIBLE (-5575 2750);
FORCEPROP 2 LAST CDS_LIB mstr_standard
J 0
(-5575 2800);
PAINT MONO (-5575 2800);
DISPLAY INVISIBLE (-5575 2800);
FORCEPROP 1 LAST PATH I48
J 0
(-5577 2800);
DISPLAY 0.872340 (-5577 2800);
PAINT GREEN (-5577 2800);
DISPLAY INVISIBLE (-5577 2800);
FORCEADD TAP..6
(-5575 2900);
FORCEPROP 3 LASTPIN (-5525 2900) SIG_NAME M_C_DQ<27>
J 0
(-5515 2910);
DISPLAY 0.659574 (-5515 2910);
PAINT MONO (-5515 2910);
DISPLAY INVISIBLE (-5515 2910);
FORCEPROP 1 LASTPIN (-5525 2900) BN 27
J 0
(-5577 2908);
DISPLAY 0.617021 (-5577 2908);
PAINT PINK (-5577 2908);
FORCEPROP 1 LAST HDL_TAP TRUE
J 0
(-5250 2775);
DISPLAY 1.595745 (-5250 2775);
PAINT GREEN (-5250 2775);
DISPLAY INVISIBLE (-5250 2775);
FORCEPROP 1 LAST BODY_TYPE PLUMBING
J 0
(-5575 2850);
DISPLAY 1.595745 (-5575 2850);
PAINT GREEN (-5575 2850);
DISPLAY INVISIBLE (-5575 2850);
FORCEPROP 2 LAST CDS_LIB mstr_standard
J 0
(-5575 2900);
PAINT MONO (-5575 2900);
DISPLAY INVISIBLE (-5575 2900);
FORCEPROP 1 LAST PATH I49
J 0
(-5577 2900);
DISPLAY 0.872340 (-5577 2900);
PAINT GREEN (-5577 2900);
DISPLAY INVISIBLE (-5577 2900);
FORCEADD TAP..6
(-5575 650);
FORCEPROP 3 LASTPIN (-5525 650) SIG_NAME M_C_CLK_DN<0>
J 0
(-5515 660);
DISPLAY 0.659574 (-5515 660);
PAINT MONO (-5515 660);
DISPLAY INVISIBLE (-5515 660);
FORCEPROP 1 LASTPIN (-5525 650) BN 0
J 0
(-5577 658);
DISPLAY 0.617021 (-5577 658);
PAINT PINK (-5577 658);
FORCEPROP 1 LAST HDL_TAP TRUE
J 0
(-5250 525);
DISPLAY 1.595745 (-5250 525);
PAINT GREEN (-5250 525);
DISPLAY INVISIBLE (-5250 525);
FORCEPROP 1 LAST BODY_TYPE PLUMBING
J 0
(-5575 600);
DISPLAY 1.595745 (-5575 600);
PAINT GREEN (-5575 600);
DISPLAY INVISIBLE (-5575 600);
FORCEPROP 2 LAST CDS_LIB mstr_standard
J 0
(-5575 650);
PAINT MONO (-5575 650);
DISPLAY INVISIBLE (-5575 650);
FORCEPROP 1 LAST PATH I5
J 0
(-5577 650);
DISPLAY 0.872340 (-5577 650);
PAINT GREEN (-5577 650);
DISPLAY INVISIBLE (-5577 650);
FORCEADD TAP..6
(-5575 2950);
FORCEPROP 3 LASTPIN (-5525 2950) SIG_NAME M_C_DQ<28>
J 0
(-5515 2960);
DISPLAY 0.659574 (-5515 2960);
PAINT MONO (-5515 2960);
DISPLAY INVISIBLE (-5515 2960);
FORCEPROP 1 LASTPIN (-5525 2950) BN 28
J 0
(-5577 2958);
DISPLAY 0.617021 (-5577 2958);
PAINT PINK (-5577 2958);
FORCEPROP 1 LAST HDL_TAP TRUE
J 0
(-5250 2825);
DISPLAY 1.595745 (-5250 2825);
PAINT GREEN (-5250 2825);
DISPLAY INVISIBLE (-5250 2825);
FORCEPROP 1 LAST BODY_TYPE PLUMBING
J 0
(-5575 2900);
DISPLAY 1.595745 (-5575 2900);
PAINT GREEN (-5575 2900);
DISPLAY INVISIBLE (-5575 2900);
FORCEPROP 2 LAST CDS_LIB mstr_standard
J 0
(-5575 2950);
PAINT MONO (-5575 2950);
DISPLAY INVISIBLE (-5575 2950);
FORCEPROP 1 LAST PATH I50
J 0
(-5577 2950);
DISPLAY 0.872340 (-5577 2950);
PAINT GREEN (-5577 2950);
DISPLAY INVISIBLE (-5577 2950);
FORCEADD TAP..6
(-5575 3000);
FORCEPROP 3 LASTPIN (-5525 3000) SIG_NAME M_C_DQ<29>
J 0
(-5515 3010);
DISPLAY 0.659574 (-5515 3010);
PAINT MONO (-5515 3010);
DISPLAY INVISIBLE (-5515 3010);
FORCEPROP 1 LASTPIN (-5525 3000) BN 29
J 0
(-5577 3008);
DISPLAY 0.617021 (-5577 3008);
PAINT PINK (-5577 3008);
FORCEPROP 1 LAST HDL_TAP TRUE
J 0
(-5250 2875);
DISPLAY 1.595745 (-5250 2875);
PAINT GREEN (-5250 2875);
DISPLAY INVISIBLE (-5250 2875);
FORCEPROP 1 LAST BODY_TYPE PLUMBING
J 0
(-5575 2950);
DISPLAY 1.595745 (-5575 2950);
PAINT GREEN (-5575 2950);
DISPLAY INVISIBLE (-5575 2950);
FORCEPROP 2 LAST CDS_LIB mstr_standard
J 0
(-5575 3000);
PAINT MONO (-5575 3000);
DISPLAY INVISIBLE (-5575 3000);
FORCEPROP 1 LAST PATH I51
J 0
(-5577 3000);
DISPLAY 0.872340 (-5577 3000);
PAINT GREEN (-5577 3000);
DISPLAY INVISIBLE (-5577 3000);
FORCEADD TAP..6
(-5575 3050);
FORCEPROP 3 LASTPIN (-5525 3050) SIG_NAME M_C_DQ<30>
J 0
(-5515 3060);
DISPLAY 0.659574 (-5515 3060);
PAINT MONO (-5515 3060);
DISPLAY INVISIBLE (-5515 3060);
FORCEPROP 1 LASTPIN (-5525 3050) BN 30
J 0
(-5577 3058);
DISPLAY 0.617021 (-5577 3058);
PAINT PINK (-5577 3058);
FORCEPROP 1 LAST HDL_TAP TRUE
J 0
(-5250 2925);
DISPLAY 1.595745 (-5250 2925);
PAINT GREEN (-5250 2925);
DISPLAY INVISIBLE (-5250 2925);
FORCEPROP 1 LAST BODY_TYPE PLUMBING
J 0
(-5575 3000);
DISPLAY 1.595745 (-5575 3000);
PAINT GREEN (-5575 3000);
DISPLAY INVISIBLE (-5575 3000);
FORCEPROP 2 LAST CDS_LIB mstr_standard
J 0
(-5575 3050);
PAINT MONO (-5575 3050);
DISPLAY INVISIBLE (-5575 3050);
FORCEPROP 1 LAST PATH I52
J 0
(-5577 3050);
DISPLAY 0.872340 (-5577 3050);
PAINT GREEN (-5577 3050);
DISPLAY INVISIBLE (-5577 3050);
FORCEADD TAP..6
(-5575 3100);
FORCEPROP 3 LASTPIN (-5525 3100) SIG_NAME M_C_DQ<31>
J 0
(-5515 3110);
DISPLAY 0.659574 (-5515 3110);
PAINT MONO (-5515 3110);
DISPLAY INVISIBLE (-5515 3110);
FORCEPROP 1 LASTPIN (-5525 3100) BN 31
J 0
(-5577 3108);
DISPLAY 0.617021 (-5577 3108);
PAINT PINK (-5577 3108);
FORCEPROP 1 LAST HDL_TAP TRUE
J 0
(-5250 2975);
DISPLAY 1.595745 (-5250 2975);
PAINT GREEN (-5250 2975);
DISPLAY INVISIBLE (-5250 2975);
FORCEPROP 1 LAST BODY_TYPE PLUMBING
J 0
(-5575 3050);
DISPLAY 1.595745 (-5575 3050);
PAINT GREEN (-5575 3050);
DISPLAY INVISIBLE (-5575 3050);
FORCEPROP 2 LAST CDS_LIB mstr_standard
J 0
(-5575 3100);
PAINT MONO (-5575 3100);
DISPLAY INVISIBLE (-5575 3100);
FORCEPROP 1 LAST PATH I53
J 0
(-5577 3100);
DISPLAY 0.872340 (-5577 3100);
PAINT GREEN (-5577 3100);
DISPLAY INVISIBLE (-5577 3100);
FORCEADD TAP..6
(-5575 3200);
FORCEPROP 3 LASTPIN (-5525 3200) SIG_NAME M_C_DQ<33>
J 0
(-5515 3210);
DISPLAY 0.659574 (-5515 3210);
PAINT MONO (-5515 3210);
DISPLAY INVISIBLE (-5515 3210);
FORCEPROP 1 LASTPIN (-5525 3200) BN 33
J 0
(-5577 3208);
DISPLAY 0.617021 (-5577 3208);
PAINT PINK (-5577 3208);
FORCEPROP 1 LAST HDL_TAP TRUE
J 0
(-5250 3075);
DISPLAY 1.595745 (-5250 3075);
PAINT GREEN (-5250 3075);
DISPLAY INVISIBLE (-5250 3075);
FORCEPROP 1 LAST BODY_TYPE PLUMBING
J 0
(-5575 3150);
DISPLAY 1.595745 (-5575 3150);
PAINT GREEN (-5575 3150);
DISPLAY INVISIBLE (-5575 3150);
FORCEPROP 2 LAST CDS_LIB mstr_standard
J 0
(-5575 3200);
PAINT MONO (-5575 3200);
DISPLAY INVISIBLE (-5575 3200);
FORCEPROP 1 LAST PATH I54
J 0
(-5577 3200);
DISPLAY 0.872340 (-5577 3200);
PAINT GREEN (-5577 3200);
DISPLAY INVISIBLE (-5577 3200);
FORCEADD TAP..6
(-5575 3250);
FORCEPROP 3 LASTPIN (-5525 3250) SIG_NAME M_C_DQ<34>
J 0
(-5515 3260);
DISPLAY 0.659574 (-5515 3260);
PAINT MONO (-5515 3260);
DISPLAY INVISIBLE (-5515 3260);
FORCEPROP 1 LASTPIN (-5525 3250) BN 34
J 0
(-5577 3258);
DISPLAY 0.617021 (-5577 3258);
PAINT PINK (-5577 3258);
FORCEPROP 1 LAST HDL_TAP TRUE
J 0
(-5250 3125);
DISPLAY 1.595745 (-5250 3125);
PAINT GREEN (-5250 3125);
DISPLAY INVISIBLE (-5250 3125);
FORCEPROP 1 LAST BODY_TYPE PLUMBING
J 0
(-5575 3200);
DISPLAY 1.595745 (-5575 3200);
PAINT GREEN (-5575 3200);
DISPLAY INVISIBLE (-5575 3200);
FORCEPROP 2 LAST CDS_LIB mstr_standard
J 0
(-5575 3250);
PAINT MONO (-5575 3250);
DISPLAY INVISIBLE (-5575 3250);
FORCEPROP 1 LAST PATH I55
J 0
(-5577 3250);
DISPLAY 0.872340 (-5577 3250);
PAINT GREEN (-5577 3250);
DISPLAY INVISIBLE (-5577 3250);
FORCEADD TAP..6
(-5575 3150);
FORCEPROP 3 LASTPIN (-5525 3150) SIG_NAME M_C_DQ<32>
J 0
(-5515 3160);
DISPLAY 0.659574 (-5515 3160);
PAINT MONO (-5515 3160);
DISPLAY INVISIBLE (-5515 3160);
FORCEPROP 1 LASTPIN (-5525 3150) BN 32
J 0
(-5577 3158);
DISPLAY 0.617021 (-5577 3158);
PAINT PINK (-5577 3158);
FORCEPROP 1 LAST HDL_TAP TRUE
J 0
(-5250 3025);
DISPLAY 1.595745 (-5250 3025);
PAINT GREEN (-5250 3025);
DISPLAY INVISIBLE (-5250 3025);
FORCEPROP 1 LAST BODY_TYPE PLUMBING
J 0
(-5575 3100);
DISPLAY 1.595745 (-5575 3100);
PAINT GREEN (-5575 3100);
DISPLAY INVISIBLE (-5575 3100);
FORCEPROP 2 LAST CDS_LIB mstr_standard
J 0
(-5575 3150);
PAINT MONO (-5575 3150);
DISPLAY INVISIBLE (-5575 3150);
FORCEPROP 1 LAST PATH I56
J 0
(-5577 3150);
DISPLAY 0.872340 (-5577 3150);
PAINT GREEN (-5577 3150);
DISPLAY INVISIBLE (-5577 3150);
FORCEADD TAP..6
(-5575 3350);
FORCEPROP 3 LASTPIN (-5525 3350) SIG_NAME M_C_DQ<36>
J 0
(-5515 3360);
DISPLAY 0.659574 (-5515 3360);
PAINT MONO (-5515 3360);
DISPLAY INVISIBLE (-5515 3360);
FORCEPROP 1 LASTPIN (-5525 3350) BN 36
J 0
(-5577 3358);
DISPLAY 0.617021 (-5577 3358);
PAINT PINK (-5577 3358);
FORCEPROP 1 LAST HDL_TAP TRUE
J 0
(-5250 3225);
DISPLAY 1.595745 (-5250 3225);
PAINT GREEN (-5250 3225);
DISPLAY INVISIBLE (-5250 3225);
FORCEPROP 1 LAST BODY_TYPE PLUMBING
J 0
(-5575 3300);
DISPLAY 1.595745 (-5575 3300);
PAINT GREEN (-5575 3300);
DISPLAY INVISIBLE (-5575 3300);
FORCEPROP 2 LAST CDS_LIB mstr_standard
J 0
(-5575 3350);
PAINT MONO (-5575 3350);
DISPLAY INVISIBLE (-5575 3350);
FORCEPROP 1 LAST PATH I57
J 0
(-5577 3350);
DISPLAY 0.872340 (-5577 3350);
PAINT GREEN (-5577 3350);
DISPLAY INVISIBLE (-5577 3350);
FORCEADD TAP..6
(-5575 3300);
FORCEPROP 3 LASTPIN (-5525 3300) SIG_NAME M_C_DQ<35>
J 0
(-5515 3310);
DISPLAY 0.659574 (-5515 3310);
PAINT MONO (-5515 3310);
DISPLAY INVISIBLE (-5515 3310);
FORCEPROP 1 LASTPIN (-5525 3300) BN 35
J 0
(-5577 3308);
DISPLAY 0.617021 (-5577 3308);
PAINT PINK (-5577 3308);
FORCEPROP 1 LAST HDL_TAP TRUE
J 0
(-5250 3175);
DISPLAY 1.595745 (-5250 3175);
PAINT GREEN (-5250 3175);
DISPLAY INVISIBLE (-5250 3175);
FORCEPROP 1 LAST BODY_TYPE PLUMBING
J 0
(-5575 3250);
DISPLAY 1.595745 (-5575 3250);
PAINT GREEN (-5575 3250);
DISPLAY INVISIBLE (-5575 3250);
FORCEPROP 2 LAST CDS_LIB mstr_standard
J 0
(-5575 3300);
PAINT MONO (-5575 3300);
DISPLAY INVISIBLE (-5575 3300);
FORCEPROP 1 LAST PATH I58
J 0
(-5577 3300);
DISPLAY 0.872340 (-5577 3300);
PAINT GREEN (-5577 3300);
DISPLAY INVISIBLE (-5577 3300);
FORCEADD TAP..6
(-5575 3400);
FORCEPROP 3 LASTPIN (-5525 3400) SIG_NAME M_C_DQ<37>
J 0
(-5515 3410);
DISPLAY 0.659574 (-5515 3410);
PAINT MONO (-5515 3410);
DISPLAY INVISIBLE (-5515 3410);
FORCEPROP 1 LASTPIN (-5525 3400) BN 37
J 0
(-5577 3408);
DISPLAY 0.617021 (-5577 3408);
PAINT PINK (-5577 3408);
FORCEPROP 1 LAST HDL_TAP TRUE
J 0
(-5250 3275);
DISPLAY 1.595745 (-5250 3275);
PAINT GREEN (-5250 3275);
DISPLAY INVISIBLE (-5250 3275);
FORCEPROP 1 LAST BODY_TYPE PLUMBING
J 0
(-5575 3350);
DISPLAY 1.595745 (-5575 3350);
PAINT GREEN (-5575 3350);
DISPLAY INVISIBLE (-5575 3350);
FORCEPROP 2 LAST CDS_LIB mstr_standard
J 0
(-5575 3400);
PAINT MONO (-5575 3400);
DISPLAY INVISIBLE (-5575 3400);
FORCEPROP 1 LAST PATH I59
J 0
(-5577 3400);
DISPLAY 0.872340 (-5577 3400);
PAINT GREEN (-5577 3400);
DISPLAY INVISIBLE (-5577 3400);
FORCEADD TAP..6
(-5575 700);
FORCEPROP 3 LASTPIN (-5525 700) SIG_NAME M_C_CLK_DN<1>
J 0
(-5515 710);
DISPLAY 0.659574 (-5515 710);
PAINT MONO (-5515 710);
DISPLAY INVISIBLE (-5515 710);
FORCEPROP 1 LASTPIN (-5525 700) BN 1
J 0
(-5577 708);
DISPLAY 0.617021 (-5577 708);
PAINT PINK (-5577 708);
FORCEPROP 1 LAST HDL_TAP TRUE
J 0
(-5250 575);
DISPLAY 1.595745 (-5250 575);
PAINT GREEN (-5250 575);
DISPLAY INVISIBLE (-5250 575);
FORCEPROP 1 LAST BODY_TYPE PLUMBING
J 0
(-5575 650);
DISPLAY 1.595745 (-5575 650);
PAINT GREEN (-5575 650);
DISPLAY INVISIBLE (-5575 650);
FORCEPROP 2 LAST CDS_LIB mstr_standard
J 0
(-5575 700);
PAINT MONO (-5575 700);
DISPLAY INVISIBLE (-5575 700);
FORCEPROP 1 LAST PATH I6
J 0
(-5577 700);
DISPLAY 0.872340 (-5577 700);
PAINT GREEN (-5577 700);
DISPLAY INVISIBLE (-5577 700);
FORCEADD TAP..6
(-5575 3450);
FORCEPROP 3 LASTPIN (-5525 3450) SIG_NAME M_C_DQ<38>
J 0
(-5515 3460);
DISPLAY 0.659574 (-5515 3460);
PAINT MONO (-5515 3460);
DISPLAY INVISIBLE (-5515 3460);
FORCEPROP 1 LASTPIN (-5525 3450) BN 38
J 0
(-5577 3458);
DISPLAY 0.617021 (-5577 3458);
PAINT PINK (-5577 3458);
FORCEPROP 1 LAST HDL_TAP TRUE
J 0
(-5250 3325);
DISPLAY 1.595745 (-5250 3325);
PAINT GREEN (-5250 3325);
DISPLAY INVISIBLE (-5250 3325);
FORCEPROP 1 LAST BODY_TYPE PLUMBING
J 0
(-5575 3400);
DISPLAY 1.595745 (-5575 3400);
PAINT GREEN (-5575 3400);
DISPLAY INVISIBLE (-5575 3400);
FORCEPROP 2 LAST CDS_LIB mstr_standard
J 0
(-5575 3450);
PAINT MONO (-5575 3450);
DISPLAY INVISIBLE (-5575 3450);
FORCEPROP 1 LAST PATH I60
J 0
(-5577 3450);
DISPLAY 0.872340 (-5577 3450);
PAINT GREEN (-5577 3450);
DISPLAY INVISIBLE (-5577 3450);
FORCEADD TAP..6
(-5575 3500);
FORCEPROP 3 LASTPIN (-5525 3500) SIG_NAME M_C_DQ<39>
J 0
(-5515 3510);
DISPLAY 0.659574 (-5515 3510);
PAINT MONO (-5515 3510);
DISPLAY INVISIBLE (-5515 3510);
FORCEPROP 1 LASTPIN (-5525 3500) BN 39
J 0
(-5577 3508);
DISPLAY 0.617021 (-5577 3508);
PAINT PINK (-5577 3508);
FORCEPROP 1 LAST HDL_TAP TRUE
J 0
(-5250 3375);
DISPLAY 1.595745 (-5250 3375);
PAINT GREEN (-5250 3375);
DISPLAY INVISIBLE (-5250 3375);
FORCEPROP 1 LAST BODY_TYPE PLUMBING
J 0
(-5575 3450);
DISPLAY 1.595745 (-5575 3450);
PAINT GREEN (-5575 3450);
DISPLAY INVISIBLE (-5575 3450);
FORCEPROP 2 LAST CDS_LIB mstr_standard
J 0
(-5575 3500);
PAINT MONO (-5575 3500);
DISPLAY INVISIBLE (-5575 3500);
FORCEPROP 1 LAST PATH I61
J 0
(-5577 3500);
DISPLAY 0.872340 (-5577 3500);
PAINT GREEN (-5577 3500);
DISPLAY INVISIBLE (-5577 3500);
FORCEADD TAP..6
(-5575 3600);
FORCEPROP 3 LASTPIN (-5525 3600) SIG_NAME M_C_DQ<41>
J 0
(-5515 3610);
DISPLAY 0.659574 (-5515 3610);
PAINT MONO (-5515 3610);
DISPLAY INVISIBLE (-5515 3610);
FORCEPROP 1 LASTPIN (-5525 3600) BN 41
J 0
(-5577 3608);
DISPLAY 0.617021 (-5577 3608);
PAINT PINK (-5577 3608);
FORCEPROP 1 LAST HDL_TAP TRUE
J 0
(-5250 3475);
DISPLAY 1.595745 (-5250 3475);
PAINT GREEN (-5250 3475);
DISPLAY INVISIBLE (-5250 3475);
FORCEPROP 1 LAST BODY_TYPE PLUMBING
J 0
(-5575 3550);
DISPLAY 1.595745 (-5575 3550);
PAINT GREEN (-5575 3550);
DISPLAY INVISIBLE (-5575 3550);
FORCEPROP 2 LAST CDS_LIB mstr_standard
J 0
(-5575 3600);
PAINT MONO (-5575 3600);
DISPLAY INVISIBLE (-5575 3600);
FORCEPROP 1 LAST PATH I62
J 0
(-5577 3600);
DISPLAY 0.872340 (-5577 3600);
PAINT GREEN (-5577 3600);
DISPLAY INVISIBLE (-5577 3600);
FORCEADD TAP..6
(-5575 3550);
FORCEPROP 3 LASTPIN (-5525 3550) SIG_NAME M_C_DQ<40>
J 0
(-5515 3560);
DISPLAY 0.659574 (-5515 3560);
PAINT MONO (-5515 3560);
DISPLAY INVISIBLE (-5515 3560);
FORCEPROP 1 LASTPIN (-5525 3550) BN 40
J 0
(-5577 3558);
DISPLAY 0.617021 (-5577 3558);
PAINT PINK (-5577 3558);
FORCEPROP 1 LAST HDL_TAP TRUE
J 0
(-5250 3425);
DISPLAY 1.595745 (-5250 3425);
PAINT GREEN (-5250 3425);
DISPLAY INVISIBLE (-5250 3425);
FORCEPROP 1 LAST BODY_TYPE PLUMBING
J 0
(-5575 3500);
DISPLAY 1.595745 (-5575 3500);
PAINT GREEN (-5575 3500);
DISPLAY INVISIBLE (-5575 3500);
FORCEPROP 2 LAST CDS_LIB mstr_standard
J 0
(-5575 3550);
PAINT MONO (-5575 3550);
DISPLAY INVISIBLE (-5575 3550);
FORCEPROP 1 LAST PATH I63
J 0
(-5577 3550);
DISPLAY 0.872340 (-5577 3550);
PAINT GREEN (-5577 3550);
DISPLAY INVISIBLE (-5577 3550);
FORCEADD TAP..6
(-5575 3650);
FORCEPROP 3 LASTPIN (-5525 3650) SIG_NAME M_C_DQ<42>
J 0
(-5515 3660);
DISPLAY 0.659574 (-5515 3660);
PAINT MONO (-5515 3660);
DISPLAY INVISIBLE (-5515 3660);
FORCEPROP 1 LASTPIN (-5525 3650) BN 42
J 0
(-5577 3658);
DISPLAY 0.617021 (-5577 3658);
PAINT PINK (-5577 3658);
FORCEPROP 1 LAST HDL_TAP TRUE
J 0
(-5250 3525);
DISPLAY 1.595745 (-5250 3525);
PAINT GREEN (-5250 3525);
DISPLAY INVISIBLE (-5250 3525);
FORCEPROP 1 LAST BODY_TYPE PLUMBING
J 0
(-5575 3600);
DISPLAY 1.595745 (-5575 3600);
PAINT GREEN (-5575 3600);
DISPLAY INVISIBLE (-5575 3600);
FORCEPROP 2 LAST CDS_LIB mstr_standard
J 0
(-5575 3650);
PAINT MONO (-5575 3650);
DISPLAY INVISIBLE (-5575 3650);
FORCEPROP 1 LAST PATH I64
J 0
(-5577 3650);
DISPLAY 0.872340 (-5577 3650);
PAINT GREEN (-5577 3650);
DISPLAY INVISIBLE (-5577 3650);
FORCEADD TAP..6
(-5575 3700);
FORCEPROP 3 LASTPIN (-5525 3700) SIG_NAME M_C_DQ<43>
J 0
(-5515 3710);
DISPLAY 0.659574 (-5515 3710);
PAINT MONO (-5515 3710);
DISPLAY INVISIBLE (-5515 3710);
FORCEPROP 1 LASTPIN (-5525 3700) BN 43
J 0
(-5577 3708);
DISPLAY 0.617021 (-5577 3708);
PAINT PINK (-5577 3708);
FORCEPROP 1 LAST HDL_TAP TRUE
J 0
(-5250 3575);
DISPLAY 1.595745 (-5250 3575);
PAINT GREEN (-5250 3575);
DISPLAY INVISIBLE (-5250 3575);
FORCEPROP 1 LAST BODY_TYPE PLUMBING
J 0
(-5575 3650);
DISPLAY 1.595745 (-5575 3650);
PAINT GREEN (-5575 3650);
DISPLAY INVISIBLE (-5575 3650);
FORCEPROP 2 LAST CDS_LIB mstr_standard
J 0
(-5575 3700);
PAINT MONO (-5575 3700);
DISPLAY INVISIBLE (-5575 3700);
FORCEPROP 1 LAST PATH I65
J 0
(-5577 3700);
DISPLAY 0.872340 (-5577 3700);
PAINT GREEN (-5577 3700);
DISPLAY INVISIBLE (-5577 3700);
FORCEADD TAP..6
(-5575 3750);
FORCEPROP 3 LASTPIN (-5525 3750) SIG_NAME M_C_DQ<44>
J 0
(-5515 3760);
DISPLAY 0.659574 (-5515 3760);
PAINT MONO (-5515 3760);
DISPLAY INVISIBLE (-5515 3760);
FORCEPROP 1 LASTPIN (-5525 3750) BN 44
J 0
(-5577 3758);
DISPLAY 0.617021 (-5577 3758);
PAINT PINK (-5577 3758);
FORCEPROP 1 LAST HDL_TAP TRUE
J 0
(-5250 3625);
DISPLAY 1.595745 (-5250 3625);
PAINT GREEN (-5250 3625);
DISPLAY INVISIBLE (-5250 3625);
FORCEPROP 1 LAST BODY_TYPE PLUMBING
J 0
(-5575 3700);
DISPLAY 1.595745 (-5575 3700);
PAINT GREEN (-5575 3700);
DISPLAY INVISIBLE (-5575 3700);
FORCEPROP 2 LAST CDS_LIB mstr_standard
J 0
(-5575 3750);
PAINT MONO (-5575 3750);
DISPLAY INVISIBLE (-5575 3750);
FORCEPROP 1 LAST PATH I66
J 0
(-5577 3750);
DISPLAY 0.872340 (-5577 3750);
PAINT GREEN (-5577 3750);
DISPLAY INVISIBLE (-5577 3750);
FORCEADD TAP..6
(-5575 3800);
FORCEPROP 3 LASTPIN (-5525 3800) SIG_NAME M_C_DQ<45>
J 0
(-5515 3810);
DISPLAY 0.659574 (-5515 3810);
PAINT MONO (-5515 3810);
DISPLAY INVISIBLE (-5515 3810);
FORCEPROP 1 LASTPIN (-5525 3800) BN 45
J 0
(-5577 3808);
DISPLAY 0.617021 (-5577 3808);
PAINT PINK (-5577 3808);
FORCEPROP 1 LAST HDL_TAP TRUE
J 0
(-5250 3675);
DISPLAY 1.595745 (-5250 3675);
PAINT GREEN (-5250 3675);
DISPLAY INVISIBLE (-5250 3675);
FORCEPROP 1 LAST BODY_TYPE PLUMBING
J 0
(-5575 3750);
DISPLAY 1.595745 (-5575 3750);
PAINT GREEN (-5575 3750);
DISPLAY INVISIBLE (-5575 3750);
FORCEPROP 2 LAST CDS_LIB mstr_standard
J 0
(-5575 3800);
PAINT MONO (-5575 3800);
DISPLAY INVISIBLE (-5575 3800);
FORCEPROP 1 LAST PATH I67
J 0
(-5577 3800);
DISPLAY 0.872340 (-5577 3800);
PAINT GREEN (-5577 3800);
DISPLAY INVISIBLE (-5577 3800);
FORCEADD TAP..6
(-5575 3850);
FORCEPROP 3 LASTPIN (-5525 3850) SIG_NAME M_C_DQ<46>
J 0
(-5515 3860);
DISPLAY 0.659574 (-5515 3860);
PAINT MONO (-5515 3860);
DISPLAY INVISIBLE (-5515 3860);
FORCEPROP 1 LASTPIN (-5525 3850) BN 46
J 0
(-5577 3858);
DISPLAY 0.617021 (-5577 3858);
PAINT PINK (-5577 3858);
FORCEPROP 1 LAST HDL_TAP TRUE
J 0
(-5250 3725);
DISPLAY 1.595745 (-5250 3725);
PAINT GREEN (-5250 3725);
DISPLAY INVISIBLE (-5250 3725);
FORCEPROP 1 LAST BODY_TYPE PLUMBING
J 0
(-5575 3800);
DISPLAY 1.595745 (-5575 3800);
PAINT GREEN (-5575 3800);
DISPLAY INVISIBLE (-5575 3800);
FORCEPROP 2 LAST CDS_LIB mstr_standard
J 0
(-5575 3850);
PAINT MONO (-5575 3850);
DISPLAY INVISIBLE (-5575 3850);
FORCEPROP 1 LAST PATH I68
J 0
(-5577 3850);
DISPLAY 0.872340 (-5577 3850);
PAINT GREEN (-5577 3850);
DISPLAY INVISIBLE (-5577 3850);
FORCEADD TAP..6
(-5575 3900);
FORCEPROP 3 LASTPIN (-5525 3900) SIG_NAME M_C_DQ<47>
J 0
(-5515 3910);
DISPLAY 0.659574 (-5515 3910);
PAINT MONO (-5515 3910);
DISPLAY INVISIBLE (-5515 3910);
FORCEPROP 1 LASTPIN (-5525 3900) BN 47
J 0
(-5577 3908);
DISPLAY 0.617021 (-5577 3908);
PAINT PINK (-5577 3908);
FORCEPROP 1 LAST HDL_TAP TRUE
J 0
(-5250 3775);
DISPLAY 1.595745 (-5250 3775);
PAINT GREEN (-5250 3775);
DISPLAY INVISIBLE (-5250 3775);
FORCEPROP 1 LAST BODY_TYPE PLUMBING
J 0
(-5575 3850);
DISPLAY 1.595745 (-5575 3850);
PAINT GREEN (-5575 3850);
DISPLAY INVISIBLE (-5575 3850);
FORCEPROP 2 LAST CDS_LIB mstr_standard
J 0
(-5575 3900);
PAINT MONO (-5575 3900);
DISPLAY INVISIBLE (-5575 3900);
FORCEPROP 1 LAST PATH I69
J 0
(-5577 3900);
DISPLAY 0.872340 (-5577 3900);
PAINT GREEN (-5577 3900);
DISPLAY INVISIBLE (-5577 3900);
FORCEADD TAP..6
(-5575 750);
FORCEPROP 3 LASTPIN (-5525 750) SIG_NAME M_C_CLK_DN<2>
J 0
(-5515 760);
DISPLAY 0.659574 (-5515 760);
PAINT MONO (-5515 760);
DISPLAY INVISIBLE (-5515 760);
FORCEPROP 1 LASTPIN (-5525 750) BN 2
J 0
(-5577 758);
DISPLAY 0.617021 (-5577 758);
PAINT PINK (-5577 758);
FORCEPROP 1 LAST HDL_TAP TRUE
J 0
(-5250 625);
DISPLAY 1.595745 (-5250 625);
PAINT GREEN (-5250 625);
DISPLAY INVISIBLE (-5250 625);
FORCEPROP 1 LAST BODY_TYPE PLUMBING
J 0
(-5575 700);
DISPLAY 1.595745 (-5575 700);
PAINT GREEN (-5575 700);
DISPLAY INVISIBLE (-5575 700);
FORCEPROP 2 LAST CDS_LIB mstr_standard
J 0
(-5575 750);
PAINT MONO (-5575 750);
DISPLAY INVISIBLE (-5575 750);
FORCEPROP 1 LAST PATH I7
J 0
(-5577 750);
DISPLAY 0.872340 (-5577 750);
PAINT GREEN (-5577 750);
DISPLAY INVISIBLE (-5577 750);
FORCEADD TAP..6
(-5575 3950);
FORCEPROP 3 LASTPIN (-5525 3950) SIG_NAME M_C_DQ<48>
J 0
(-5515 3960);
DISPLAY 0.659574 (-5515 3960);
PAINT MONO (-5515 3960);
DISPLAY INVISIBLE (-5515 3960);
FORCEPROP 1 LASTPIN (-5525 3950) BN 48
J 0
(-5577 3958);
DISPLAY 0.617021 (-5577 3958);
PAINT PINK (-5577 3958);
FORCEPROP 1 LAST HDL_TAP TRUE
J 0
(-5250 3825);
DISPLAY 1.595745 (-5250 3825);
PAINT GREEN (-5250 3825);
DISPLAY INVISIBLE (-5250 3825);
FORCEPROP 1 LAST BODY_TYPE PLUMBING
J 0
(-5575 3900);
DISPLAY 1.595745 (-5575 3900);
PAINT GREEN (-5575 3900);
DISPLAY INVISIBLE (-5575 3900);
FORCEPROP 2 LAST CDS_LIB mstr_standard
J 0
(-5575 3950);
PAINT MONO (-5575 3950);
DISPLAY INVISIBLE (-5575 3950);
FORCEPROP 1 LAST PATH I70
J 0
(-5577 3950);
DISPLAY 0.872340 (-5577 3950);
PAINT GREEN (-5577 3950);
DISPLAY INVISIBLE (-5577 3950);
FORCEADD TAP..6
(-5575 4000);
FORCEPROP 3 LASTPIN (-5525 4000) SIG_NAME M_C_DQ<49>
J 0
(-5515 4010);
DISPLAY 0.659574 (-5515 4010);
PAINT MONO (-5515 4010);
DISPLAY INVISIBLE (-5515 4010);
FORCEPROP 1 LASTPIN (-5525 4000) BN 49
J 0
(-5577 4008);
DISPLAY 0.617021 (-5577 4008);
PAINT PINK (-5577 4008);
FORCEPROP 1 LAST HDL_TAP TRUE
J 0
(-5250 3875);
DISPLAY 1.595745 (-5250 3875);
PAINT GREEN (-5250 3875);
DISPLAY INVISIBLE (-5250 3875);
FORCEPROP 1 LAST BODY_TYPE PLUMBING
J 0
(-5575 3950);
DISPLAY 1.595745 (-5575 3950);
PAINT GREEN (-5575 3950);
DISPLAY INVISIBLE (-5575 3950);
FORCEPROP 2 LAST CDS_LIB mstr_standard
J 0
(-5575 4000);
PAINT MONO (-5575 4000);
DISPLAY INVISIBLE (-5575 4000);
FORCEPROP 1 LAST PATH I71
J 0
(-5577 4000);
DISPLAY 0.872340 (-5577 4000);
PAINT GREEN (-5577 4000);
DISPLAY INVISIBLE (-5577 4000);
FORCEADD OFFPAGE..6
(-6425 4825);
FORCEPROP 2 LAST $XR1 48 
J 0
(-6764 4825);
DISPLAY 0.638298 (-6764 4825);
PAINT MONO (-6764 4825);
FORCEPROP 2 LAST $XR0 47 
J 0
(-6674 4825);
DISPLAY 0.638298 (-6674 4825);
PAINT MONO (-6674 4825);
FORCEPROP 1 LAST COMMENT_BODY TRUE
J 0
(-6325 4750);
DISPLAY 1.170213 (-6325 4750);
PAINT GREEN (-6325 4750);
DISPLAY INVISIBLE (-6325 4750);
FORCEPROP 1 LAST OFFPAGE TRUE
J 0
(-6100 4700);
DISPLAY 1.170213 (-6100 4700);
PAINT GREEN (-6100 4700);
DISPLAY INVISIBLE (-6100 4700);
FORCEPROP 2 LAST CDS_LIB mstr_standard
J 0
(-6425 4825);
PAINT MONO (-6425 4825);
DISPLAY INVISIBLE (-6425 4825);
FORCEPROP 2 LAST PATH I72
J 0
(-6375 4900);
DISPLAY 1.021277 (-6375 4900);
PAINT ORANGE (-6375 4900);
DISPLAY INVISIBLE (-6375 4900);
FORCEADD TAP..6
(-5575 4100);
FORCEPROP 3 LASTPIN (-5525 4100) SIG_NAME M_C_DQ<51>
J 0
(-5515 4110);
DISPLAY 0.659574 (-5515 4110);
PAINT MONO (-5515 4110);
DISPLAY INVISIBLE (-5515 4110);
FORCEPROP 1 LASTPIN (-5525 4100) BN 51
J 0
(-5577 4108);
DISPLAY 0.617021 (-5577 4108);
PAINT PINK (-5577 4108);
FORCEPROP 1 LAST HDL_TAP TRUE
J 0
(-5250 3975);
DISPLAY 1.595745 (-5250 3975);
PAINT GREEN (-5250 3975);
DISPLAY INVISIBLE (-5250 3975);
FORCEPROP 1 LAST BODY_TYPE PLUMBING
J 0
(-5575 4050);
DISPLAY 1.595745 (-5575 4050);
PAINT GREEN (-5575 4050);
DISPLAY INVISIBLE (-5575 4050);
FORCEPROP 2 LAST CDS_LIB mstr_standard
J 0
(-5575 4100);
PAINT MONO (-5575 4100);
DISPLAY INVISIBLE (-5575 4100);
FORCEPROP 1 LAST PATH I73
J 0
(-5577 4100);
DISPLAY 0.872340 (-5577 4100);
PAINT GREEN (-5577 4100);
DISPLAY INVISIBLE (-5577 4100);
FORCEADD TAP..6
(-5575 4050);
FORCEPROP 3 LASTPIN (-5525 4050) SIG_NAME M_C_DQ<50>
J 0
(-5515 4060);
DISPLAY 0.659574 (-5515 4060);
PAINT MONO (-5515 4060);
DISPLAY INVISIBLE (-5515 4060);
FORCEPROP 1 LASTPIN (-5525 4050) BN 50
J 0
(-5577 4058);
DISPLAY 0.617021 (-5577 4058);
PAINT PINK (-5577 4058);
FORCEPROP 1 LAST HDL_TAP TRUE
J 0
(-5250 3925);
DISPLAY 1.595745 (-5250 3925);
PAINT GREEN (-5250 3925);
DISPLAY INVISIBLE (-5250 3925);
FORCEPROP 1 LAST BODY_TYPE PLUMBING
J 0
(-5575 4000);
DISPLAY 1.595745 (-5575 4000);
PAINT GREEN (-5575 4000);
DISPLAY INVISIBLE (-5575 4000);
FORCEPROP 2 LAST CDS_LIB mstr_standard
J 0
(-5575 4050);
PAINT MONO (-5575 4050);
DISPLAY INVISIBLE (-5575 4050);
FORCEPROP 1 LAST PATH I74
J 0
(-5577 4050);
DISPLAY 0.872340 (-5577 4050);
PAINT GREEN (-5577 4050);
DISPLAY INVISIBLE (-5577 4050);
FORCEADD TAP..6
(-5575 4150);
FORCEPROP 3 LASTPIN (-5525 4150) SIG_NAME M_C_DQ<52>
J 0
(-5515 4160);
DISPLAY 0.659574 (-5515 4160);
PAINT MONO (-5515 4160);
DISPLAY INVISIBLE (-5515 4160);
FORCEPROP 1 LASTPIN (-5525 4150) BN 52
J 0
(-5577 4158);
DISPLAY 0.617021 (-5577 4158);
PAINT PINK (-5577 4158);
FORCEPROP 1 LAST HDL_TAP TRUE
J 0
(-5250 4025);
DISPLAY 1.595745 (-5250 4025);
PAINT GREEN (-5250 4025);
DISPLAY INVISIBLE (-5250 4025);
FORCEPROP 1 LAST BODY_TYPE PLUMBING
J 0
(-5575 4100);
DISPLAY 1.595745 (-5575 4100);
PAINT GREEN (-5575 4100);
DISPLAY INVISIBLE (-5575 4100);
FORCEPROP 2 LAST CDS_LIB mstr_standard
J 0
(-5575 4150);
PAINT MONO (-5575 4150);
DISPLAY INVISIBLE (-5575 4150);
FORCEPROP 1 LAST PATH I75
J 0
(-5577 4150);
DISPLAY 0.872340 (-5577 4150);
PAINT GREEN (-5577 4150);
DISPLAY INVISIBLE (-5577 4150);
FORCEADD TAP..6
(-5575 4200);
FORCEPROP 3 LASTPIN (-5525 4200) SIG_NAME M_C_DQ<53>
J 0
(-5515 4210);
DISPLAY 0.659574 (-5515 4210);
PAINT MONO (-5515 4210);
DISPLAY INVISIBLE (-5515 4210);
FORCEPROP 1 LASTPIN (-5525 4200) BN 53
J 0
(-5577 4208);
DISPLAY 0.617021 (-5577 4208);
PAINT PINK (-5577 4208);
FORCEPROP 1 LAST HDL_TAP TRUE
J 0
(-5250 4075);
DISPLAY 1.595745 (-5250 4075);
PAINT GREEN (-5250 4075);
DISPLAY INVISIBLE (-5250 4075);
FORCEPROP 1 LAST BODY_TYPE PLUMBING
J 0
(-5575 4150);
DISPLAY 1.595745 (-5575 4150);
PAINT GREEN (-5575 4150);
DISPLAY INVISIBLE (-5575 4150);
FORCEPROP 2 LAST CDS_LIB mstr_standard
J 0
(-5575 4200);
PAINT MONO (-5575 4200);
DISPLAY INVISIBLE (-5575 4200);
FORCEPROP 1 LAST PATH I76
J 0
(-5577 4200);
DISPLAY 0.872340 (-5577 4200);
PAINT GREEN (-5577 4200);
DISPLAY INVISIBLE (-5577 4200);
FORCEADD TAP..6
(-5575 4250);
FORCEPROP 3 LASTPIN (-5525 4250) SIG_NAME M_C_DQ<54>
J 0
(-5515 4260);
DISPLAY 0.659574 (-5515 4260);
PAINT MONO (-5515 4260);
DISPLAY INVISIBLE (-5515 4260);
FORCEPROP 1 LASTPIN (-5525 4250) BN 54
J 0
(-5577 4258);
DISPLAY 0.617021 (-5577 4258);
PAINT PINK (-5577 4258);
FORCEPROP 1 LAST HDL_TAP TRUE
J 0
(-5250 4125);
DISPLAY 1.595745 (-5250 4125);
PAINT GREEN (-5250 4125);
DISPLAY INVISIBLE (-5250 4125);
FORCEPROP 1 LAST BODY_TYPE PLUMBING
J 0
(-5575 4200);
DISPLAY 1.595745 (-5575 4200);
PAINT GREEN (-5575 4200);
DISPLAY INVISIBLE (-5575 4200);
FORCEPROP 2 LAST CDS_LIB mstr_standard
J 0
(-5575 4250);
PAINT MONO (-5575 4250);
DISPLAY INVISIBLE (-5575 4250);
FORCEPROP 1 LAST PATH I77
J 0
(-5577 4250);
DISPLAY 0.872340 (-5577 4250);
PAINT GREEN (-5577 4250);
DISPLAY INVISIBLE (-5577 4250);
FORCEADD TAP..6
(-5575 4300);
FORCEPROP 3 LASTPIN (-5525 4300) SIG_NAME M_C_DQ<55>
J 0
(-5515 4310);
DISPLAY 0.659574 (-5515 4310);
PAINT MONO (-5515 4310);
DISPLAY INVISIBLE (-5515 4310);
FORCEPROP 1 LASTPIN (-5525 4300) BN 55
J 0
(-5577 4308);
DISPLAY 0.617021 (-5577 4308);
PAINT PINK (-5577 4308);
FORCEPROP 1 LAST HDL_TAP TRUE
J 0
(-5250 4175);
DISPLAY 1.595745 (-5250 4175);
PAINT GREEN (-5250 4175);
DISPLAY INVISIBLE (-5250 4175);
FORCEPROP 1 LAST BODY_TYPE PLUMBING
J 0
(-5575 4250);
DISPLAY 1.595745 (-5575 4250);
PAINT GREEN (-5575 4250);
DISPLAY INVISIBLE (-5575 4250);
FORCEPROP 2 LAST CDS_LIB mstr_standard
J 0
(-5575 4300);
PAINT MONO (-5575 4300);
DISPLAY INVISIBLE (-5575 4300);
FORCEPROP 1 LAST PATH I78
J 0
(-5577 4300);
DISPLAY 0.872340 (-5577 4300);
PAINT GREEN (-5577 4300);
DISPLAY INVISIBLE (-5577 4300);
FORCEADD TAP..6
(-5575 4350);
FORCEPROP 3 LASTPIN (-5525 4350) SIG_NAME M_C_DQ<56>
J 0
(-5515 4360);
DISPLAY 0.659574 (-5515 4360);
PAINT MONO (-5515 4360);
DISPLAY INVISIBLE (-5515 4360);
FORCEPROP 1 LASTPIN (-5525 4350) BN 56
J 0
(-5577 4358);
DISPLAY 0.617021 (-5577 4358);
PAINT PINK (-5577 4358);
FORCEPROP 1 LAST HDL_TAP TRUE
J 0
(-5250 4225);
DISPLAY 1.595745 (-5250 4225);
PAINT GREEN (-5250 4225);
DISPLAY INVISIBLE (-5250 4225);
FORCEPROP 1 LAST BODY_TYPE PLUMBING
J 0
(-5575 4300);
DISPLAY 1.595745 (-5575 4300);
PAINT GREEN (-5575 4300);
DISPLAY INVISIBLE (-5575 4300);
FORCEPROP 2 LAST CDS_LIB mstr_standard
J 0
(-5575 4350);
PAINT MONO (-5575 4350);
DISPLAY INVISIBLE (-5575 4350);
FORCEPROP 1 LAST PATH I79
J 0
(-5577 4350);
DISPLAY 0.872340 (-5577 4350);
PAINT GREEN (-5577 4350);
DISPLAY INVISIBLE (-5577 4350);
FORCEADD TAP..6
(-5575 800);
FORCEPROP 3 LASTPIN (-5525 800) SIG_NAME M_C_CLK_DN<3>
J 0
(-5515 810);
DISPLAY 0.659574 (-5515 810);
PAINT MONO (-5515 810);
DISPLAY INVISIBLE (-5515 810);
FORCEPROP 1 LASTPIN (-5525 800) BN 3
J 0
(-5577 808);
DISPLAY 0.617021 (-5577 808);
PAINT PINK (-5577 808);
FORCEPROP 1 LAST HDL_TAP TRUE
J 0
(-5250 675);
DISPLAY 1.595745 (-5250 675);
PAINT GREEN (-5250 675);
DISPLAY INVISIBLE (-5250 675);
FORCEPROP 1 LAST BODY_TYPE PLUMBING
J 0
(-5575 750);
DISPLAY 1.595745 (-5575 750);
PAINT GREEN (-5575 750);
DISPLAY INVISIBLE (-5575 750);
FORCEPROP 2 LAST CDS_LIB mstr_standard
J 0
(-5575 800);
PAINT MONO (-5575 800);
DISPLAY INVISIBLE (-5575 800);
FORCEPROP 1 LAST PATH I8
J 0
(-5577 800);
DISPLAY 0.872340 (-5577 800);
PAINT GREEN (-5577 800);
DISPLAY INVISIBLE (-5577 800);
FORCEADD TAP..6
(-5575 4400);
FORCEPROP 3 LASTPIN (-5525 4400) SIG_NAME M_C_DQ<57>
J 0
(-5515 4410);
DISPLAY 0.659574 (-5515 4410);
PAINT MONO (-5515 4410);
DISPLAY INVISIBLE (-5515 4410);
FORCEPROP 1 LASTPIN (-5525 4400) BN 57
J 0
(-5577 4408);
DISPLAY 0.617021 (-5577 4408);
PAINT PINK (-5577 4408);
FORCEPROP 1 LAST HDL_TAP TRUE
J 0
(-5250 4275);
DISPLAY 1.595745 (-5250 4275);
PAINT GREEN (-5250 4275);
DISPLAY INVISIBLE (-5250 4275);
FORCEPROP 1 LAST BODY_TYPE PLUMBING
J 0
(-5575 4350);
DISPLAY 1.595745 (-5575 4350);
PAINT GREEN (-5575 4350);
DISPLAY INVISIBLE (-5575 4350);
FORCEPROP 2 LAST CDS_LIB mstr_standard
J 0
(-5575 4400);
PAINT MONO (-5575 4400);
DISPLAY INVISIBLE (-5575 4400);
FORCEPROP 1 LAST PATH I80
J 0
(-5577 4400);
DISPLAY 0.872340 (-5577 4400);
PAINT GREEN (-5577 4400);
DISPLAY INVISIBLE (-5577 4400);
FORCEADD TAP..6
(-5575 4450);
FORCEPROP 3 LASTPIN (-5525 4450) SIG_NAME M_C_DQ<58>
J 0
(-5515 4460);
DISPLAY 0.659574 (-5515 4460);
PAINT MONO (-5515 4460);
DISPLAY INVISIBLE (-5515 4460);
FORCEPROP 1 LASTPIN (-5525 4450) BN 58
J 0
(-5577 4458);
DISPLAY 0.617021 (-5577 4458);
PAINT PINK (-5577 4458);
FORCEPROP 1 LAST HDL_TAP TRUE
J 0
(-5250 4325);
DISPLAY 1.595745 (-5250 4325);
PAINT GREEN (-5250 4325);
DISPLAY INVISIBLE (-5250 4325);
FORCEPROP 1 LAST BODY_TYPE PLUMBING
J 0
(-5575 4400);
DISPLAY 1.595745 (-5575 4400);
PAINT GREEN (-5575 4400);
DISPLAY INVISIBLE (-5575 4400);
FORCEPROP 2 LAST CDS_LIB mstr_standard
J 0
(-5575 4450);
PAINT MONO (-5575 4450);
DISPLAY INVISIBLE (-5575 4450);
FORCEPROP 1 LAST PATH I81
J 0
(-5577 4450);
DISPLAY 0.872340 (-5577 4450);
PAINT GREEN (-5577 4450);
DISPLAY INVISIBLE (-5577 4450);
FORCEADD TAP..6
(-5575 4500);
FORCEPROP 3 LASTPIN (-5525 4500) SIG_NAME M_C_DQ<59>
J 0
(-5515 4510);
DISPLAY 0.659574 (-5515 4510);
PAINT MONO (-5515 4510);
DISPLAY INVISIBLE (-5515 4510);
FORCEPROP 1 LASTPIN (-5525 4500) BN 59
J 0
(-5577 4508);
DISPLAY 0.617021 (-5577 4508);
PAINT PINK (-5577 4508);
FORCEPROP 1 LAST HDL_TAP TRUE
J 0
(-5250 4375);
DISPLAY 1.595745 (-5250 4375);
PAINT GREEN (-5250 4375);
DISPLAY INVISIBLE (-5250 4375);
FORCEPROP 1 LAST BODY_TYPE PLUMBING
J 0
(-5575 4450);
DISPLAY 1.595745 (-5575 4450);
PAINT GREEN (-5575 4450);
DISPLAY INVISIBLE (-5575 4450);
FORCEPROP 2 LAST CDS_LIB mstr_standard
J 0
(-5575 4500);
PAINT MONO (-5575 4500);
DISPLAY INVISIBLE (-5575 4500);
FORCEPROP 1 LAST PATH I82
J 0
(-5577 4500);
DISPLAY 0.872340 (-5577 4500);
PAINT GREEN (-5577 4500);
DISPLAY INVISIBLE (-5577 4500);
FORCEADD TAP..6
(-5575 4550);
FORCEPROP 3 LASTPIN (-5525 4550) SIG_NAME M_C_DQ<60>
J 0
(-5515 4560);
DISPLAY 0.659574 (-5515 4560);
PAINT MONO (-5515 4560);
DISPLAY INVISIBLE (-5515 4560);
FORCEPROP 1 LASTPIN (-5525 4550) BN 60
J 0
(-5577 4558);
DISPLAY 0.617021 (-5577 4558);
PAINT PINK (-5577 4558);
FORCEPROP 1 LAST HDL_TAP TRUE
J 0
(-5250 4425);
DISPLAY 1.595745 (-5250 4425);
PAINT GREEN (-5250 4425);
DISPLAY INVISIBLE (-5250 4425);
FORCEPROP 1 LAST BODY_TYPE PLUMBING
J 0
(-5575 4500);
DISPLAY 1.595745 (-5575 4500);
PAINT GREEN (-5575 4500);
DISPLAY INVISIBLE (-5575 4500);
FORCEPROP 2 LAST CDS_LIB mstr_standard
J 0
(-5575 4550);
PAINT MONO (-5575 4550);
DISPLAY INVISIBLE (-5575 4550);
FORCEPROP 1 LAST PATH I83
J 0
(-5577 4550);
DISPLAY 0.872340 (-5577 4550);
PAINT GREEN (-5577 4550);
DISPLAY INVISIBLE (-5577 4550);
FORCEADD TAP..6
(-5575 4600);
FORCEPROP 3 LASTPIN (-5525 4600) SIG_NAME M_C_DQ<61>
J 0
(-5515 4610);
DISPLAY 0.659574 (-5515 4610);
PAINT MONO (-5515 4610);
DISPLAY INVISIBLE (-5515 4610);
FORCEPROP 1 LASTPIN (-5525 4600) BN 61
J 0
(-5577 4608);
DISPLAY 0.617021 (-5577 4608);
PAINT PINK (-5577 4608);
FORCEPROP 1 LAST HDL_TAP TRUE
J 0
(-5250 4475);
DISPLAY 1.595745 (-5250 4475);
PAINT GREEN (-5250 4475);
DISPLAY INVISIBLE (-5250 4475);
FORCEPROP 1 LAST BODY_TYPE PLUMBING
J 0
(-5575 4550);
DISPLAY 1.595745 (-5575 4550);
PAINT GREEN (-5575 4550);
DISPLAY INVISIBLE (-5575 4550);
FORCEPROP 2 LAST CDS_LIB mstr_standard
J 0
(-5575 4600);
PAINT MONO (-5575 4600);
DISPLAY INVISIBLE (-5575 4600);
FORCEPROP 1 LAST PATH I84
J 0
(-5577 4600);
DISPLAY 0.872340 (-5577 4600);
PAINT GREEN (-5577 4600);
DISPLAY INVISIBLE (-5577 4600);
FORCEADD TAP..6
(-5575 4700);
FORCEPROP 3 LASTPIN (-5525 4700) SIG_NAME M_C_DQ<63>
J 0
(-5515 4710);
DISPLAY 0.659574 (-5515 4710);
PAINT MONO (-5515 4710);
DISPLAY INVISIBLE (-5515 4710);
FORCEPROP 1 LASTPIN (-5525 4700) BN 63
J 0
(-5577 4708);
DISPLAY 0.617021 (-5577 4708);
PAINT PINK (-5577 4708);
FORCEPROP 1 LAST HDL_TAP TRUE
J 0
(-5250 4575);
DISPLAY 1.595745 (-5250 4575);
PAINT GREEN (-5250 4575);
DISPLAY INVISIBLE (-5250 4575);
FORCEPROP 1 LAST BODY_TYPE PLUMBING
J 0
(-5575 4650);
DISPLAY 1.595745 (-5575 4650);
PAINT GREEN (-5575 4650);
DISPLAY INVISIBLE (-5575 4650);
FORCEPROP 2 LAST CDS_LIB mstr_standard
J 0
(-5575 4700);
PAINT MONO (-5575 4700);
DISPLAY INVISIBLE (-5575 4700);
FORCEPROP 1 LAST PATH I85
J 0
(-5577 4700);
DISPLAY 0.872340 (-5577 4700);
PAINT GREEN (-5577 4700);
DISPLAY INVISIBLE (-5577 4700);
FORCEADD TAP..6
(-5575 4650);
FORCEPROP 3 LASTPIN (-5525 4650) SIG_NAME M_C_DQ<62>
J 0
(-5515 4660);
DISPLAY 0.659574 (-5515 4660);
PAINT MONO (-5515 4660);
DISPLAY INVISIBLE (-5515 4660);
FORCEPROP 1 LASTPIN (-5525 4650) BN 62
J 0
(-5577 4658);
DISPLAY 0.617021 (-5577 4658);
PAINT PINK (-5577 4658);
FORCEPROP 1 LAST HDL_TAP TRUE
J 0
(-5250 4525);
DISPLAY 1.595745 (-5250 4525);
PAINT GREEN (-5250 4525);
DISPLAY INVISIBLE (-5250 4525);
FORCEPROP 1 LAST BODY_TYPE PLUMBING
J 0
(-5575 4600);
DISPLAY 1.595745 (-5575 4600);
PAINT GREEN (-5575 4600);
DISPLAY INVISIBLE (-5575 4600);
FORCEPROP 2 LAST CDS_LIB mstr_standard
J 0
(-5575 4650);
PAINT MONO (-5575 4650);
DISPLAY INVISIBLE (-5575 4650);
FORCEPROP 1 LAST PATH I86
J 0
(-5577 4650);
DISPLAY 0.872340 (-5577 4650);
PAINT GREEN (-5577 4650);
DISPLAY INVISIBLE (-5577 4650);
FORCEADD TAP..6
R 2
(-2850 750);
FORCEPROP 3 LASTPIN (-2900 750) SIG_NAME M_C_BA<0>
J 0
(-2890 760);
DISPLAY 0.659574 (-2890 760);
PAINT MONO (-2890 760);
DISPLAY INVISIBLE (-2890 760);
FORCEPROP 1 LASTPIN (-2900 750) BN 0
J 2
(-2848 758);
DISPLAY 0.617021 (-2848 758);
PAINT PINK (-2848 758);
FORCEPROP 1 LAST HDL_TAP TRUE
J 2
(-3175 625);
DISPLAY 1.595745 (-3175 625);
PAINT GREEN (-3175 625);
DISPLAY INVISIBLE (-3175 625);
FORCEPROP 1 LAST BODY_TYPE PLUMBING
J 2
(-2850 700);
DISPLAY 1.595745 (-2850 700);
PAINT GREEN (-2850 700);
DISPLAY INVISIBLE (-2850 700);
FORCEPROP 2 LAST CDS_LIB mstr_standard
J 0
(-2850 750);
PAINT MONO (-2850 750);
DISPLAY INVISIBLE (-2850 750);
FORCEPROP 1 LAST PATH I87
J 2
(-2848 750);
DISPLAY 0.872340 (-2848 750);
PAINT GREEN (-2848 750);
DISPLAY INVISIBLE (-2848 750);
FORCEADD TAP..6
R 2
(-2850 800);
FORCEPROP 3 LASTPIN (-2900 800) SIG_NAME M_C_BA<1>
J 0
(-2890 810);
DISPLAY 0.659574 (-2890 810);
PAINT MONO (-2890 810);
DISPLAY INVISIBLE (-2890 810);
FORCEPROP 1 LASTPIN (-2900 800) BN 1
J 2
(-2848 808);
DISPLAY 0.617021 (-2848 808);
PAINT PINK (-2848 808);
FORCEPROP 1 LAST HDL_TAP TRUE
J 2
(-3175 675);
DISPLAY 1.595745 (-3175 675);
PAINT GREEN (-3175 675);
DISPLAY INVISIBLE (-3175 675);
FORCEPROP 1 LAST BODY_TYPE PLUMBING
J 2
(-2850 750);
DISPLAY 1.595745 (-2850 750);
PAINT GREEN (-2850 750);
DISPLAY INVISIBLE (-2850 750);
FORCEPROP 2 LAST CDS_LIB mstr_standard
J 0
(-2850 800);
PAINT MONO (-2850 800);
DISPLAY INVISIBLE (-2850 800);
FORCEPROP 1 LAST PATH I88
J 2
(-2848 800);
DISPLAY 0.872340 (-2848 800);
PAINT GREEN (-2848 800);
DISPLAY INVISIBLE (-2848 800);
FORCEADD TAP..6
R 2
(-2850 850);
FORCEPROP 3 LASTPIN (-2900 850) SIG_NAME M_C_BG<0>
J 0
(-2890 860);
DISPLAY 0.659574 (-2890 860);
PAINT MONO (-2890 860);
DISPLAY INVISIBLE (-2890 860);
FORCEPROP 1 LASTPIN (-2900 850) BN 0
J 2
(-2848 858);
DISPLAY 0.617021 (-2848 858);
PAINT PINK (-2848 858);
FORCEPROP 1 LAST HDL_TAP TRUE
J 2
(-3175 725);
DISPLAY 1.595745 (-3175 725);
PAINT GREEN (-3175 725);
DISPLAY INVISIBLE (-3175 725);
FORCEPROP 1 LAST BODY_TYPE PLUMBING
J 2
(-2850 800);
DISPLAY 1.595745 (-2850 800);
PAINT GREEN (-2850 800);
DISPLAY INVISIBLE (-2850 800);
FORCEPROP 2 LAST CDS_LIB mstr_standard
J 0
(-2850 850);
PAINT MONO (-2850 850);
DISPLAY INVISIBLE (-2850 850);
FORCEPROP 1 LAST PATH I89
J 2
(-2848 850);
DISPLAY 0.872340 (-2848 850);
PAINT GREEN (-2848 850);
DISPLAY INVISIBLE (-2848 850);
FORCEADD TAP..6
(-5575 850);
FORCEPROP 3 LASTPIN (-5525 850) SIG_NAME M_C_CLK_DP<0>
J 0
(-5515 860);
DISPLAY 0.659574 (-5515 860);
PAINT MONO (-5515 860);
DISPLAY INVISIBLE (-5515 860);
FORCEPROP 1 LASTPIN (-5525 850) BN 0
J 0
(-5577 858);
DISPLAY 0.617021 (-5577 858);
PAINT PINK (-5577 858);
FORCEPROP 1 LAST HDL_TAP TRUE
J 0
(-5250 725);
DISPLAY 1.595745 (-5250 725);
PAINT GREEN (-5250 725);
DISPLAY INVISIBLE (-5250 725);
FORCEPROP 1 LAST BODY_TYPE PLUMBING
J 0
(-5575 800);
DISPLAY 1.595745 (-5575 800);
PAINT GREEN (-5575 800);
DISPLAY INVISIBLE (-5575 800);
FORCEPROP 2 LAST CDS_LIB mstr_standard
J 0
(-5575 850);
PAINT MONO (-5575 850);
DISPLAY INVISIBLE (-5575 850);
FORCEPROP 1 LAST PATH I9
J 0
(-5577 850);
DISPLAY 0.872340 (-5577 850);
PAINT GREEN (-5577 850);
DISPLAY INVISIBLE (-5577 850);
FORCEADD TAP..6
R 2
(-2850 900);
FORCEPROP 3 LASTPIN (-2900 900) SIG_NAME M_C_BG<1>
J 0
(-2890 910);
DISPLAY 0.659574 (-2890 910);
PAINT MONO (-2890 910);
DISPLAY INVISIBLE (-2890 910);
FORCEPROP 1 LASTPIN (-2900 900) BN 1
J 2
(-2848 908);
DISPLAY 0.617021 (-2848 908);
PAINT PINK (-2848 908);
FORCEPROP 1 LAST HDL_TAP TRUE
J 2
(-3175 775);
DISPLAY 1.595745 (-3175 775);
PAINT GREEN (-3175 775);
DISPLAY INVISIBLE (-3175 775);
FORCEPROP 1 LAST BODY_TYPE PLUMBING
J 2
(-2850 850);
DISPLAY 1.595745 (-2850 850);
PAINT GREEN (-2850 850);
DISPLAY INVISIBLE (-2850 850);
FORCEPROP 2 LAST CDS_LIB mstr_standard
J 0
(-2850 900);
PAINT MONO (-2850 900);
DISPLAY INVISIBLE (-2850 900);
FORCEPROP 1 LAST PATH I90
J 2
(-2848 900);
DISPLAY 0.872340 (-2848 900);
PAINT GREEN (-2848 900);
DISPLAY INVISIBLE (-2848 900);
FORCEADD TAP..6
R 2
(-2850 1000);
FORCEPROP 3 LASTPIN (-2900 1000) SIG_NAME M_C_CS_N<0>
J 0
(-2890 1010);
DISPLAY 0.659574 (-2890 1010);
PAINT MONO (-2890 1010);
DISPLAY INVISIBLE (-2890 1010);
FORCEPROP 1 LASTPIN (-2900 1000) BN 0
J 2
(-2848 1008);
DISPLAY 0.617021 (-2848 1008);
PAINT PINK (-2848 1008);
FORCEPROP 1 LAST HDL_TAP TRUE
J 2
(-3175 875);
DISPLAY 1.595745 (-3175 875);
PAINT GREEN (-3175 875);
DISPLAY INVISIBLE (-3175 875);
FORCEPROP 1 LAST BODY_TYPE PLUMBING
J 2
(-2850 950);
DISPLAY 1.595745 (-2850 950);
PAINT GREEN (-2850 950);
DISPLAY INVISIBLE (-2850 950);
FORCEPROP 2 LAST CDS_LIB mstr_standard
J 0
(-2850 1000);
PAINT MONO (-2850 1000);
DISPLAY INVISIBLE (-2850 1000);
FORCEPROP 1 LAST PATH I91
J 2
(-2848 1000);
DISPLAY 0.872340 (-2848 1000);
PAINT GREEN (-2848 1000);
DISPLAY INVISIBLE (-2848 1000);
FORCEADD TAP..6
R 2
(-2850 1100);
FORCEPROP 3 LASTPIN (-2900 1100) SIG_NAME M_C_CS_N<2>
J 0
(-2890 1110);
DISPLAY 0.659574 (-2890 1110);
PAINT MONO (-2890 1110);
DISPLAY INVISIBLE (-2890 1110);
FORCEPROP 1 LASTPIN (-2900 1100) BN 2
J 2
(-2848 1108);
DISPLAY 0.617021 (-2848 1108);
PAINT PINK (-2848 1108);
FORCEPROP 1 LAST HDL_TAP TRUE
J 2
(-3175 975);
DISPLAY 1.595745 (-3175 975);
PAINT GREEN (-3175 975);
DISPLAY INVISIBLE (-3175 975);
FORCEPROP 1 LAST BODY_TYPE PLUMBING
J 2
(-2850 1050);
DISPLAY 1.595745 (-2850 1050);
PAINT GREEN (-2850 1050);
DISPLAY INVISIBLE (-2850 1050);
FORCEPROP 2 LAST CDS_LIB mstr_standard
J 0
(-2850 1100);
PAINT MONO (-2850 1100);
DISPLAY INVISIBLE (-2850 1100);
FORCEPROP 1 LAST PATH I92
J 2
(-2848 1100);
DISPLAY 0.872340 (-2848 1100);
PAINT GREEN (-2848 1100);
DISPLAY INVISIBLE (-2848 1100);
FORCEADD TAP..6
R 2
(-2850 1050);
FORCEPROP 3 LASTPIN (-2900 1050) SIG_NAME M_C_CS_N<1>
J 0
(-2890 1060);
DISPLAY 0.659574 (-2890 1060);
PAINT MONO (-2890 1060);
DISPLAY INVISIBLE (-2890 1060);
FORCEPROP 1 LASTPIN (-2900 1050) BN 1
J 2
(-2848 1058);
DISPLAY 0.617021 (-2848 1058);
PAINT PINK (-2848 1058);
FORCEPROP 1 LAST HDL_TAP TRUE
J 2
(-3175 925);
DISPLAY 1.595745 (-3175 925);
PAINT GREEN (-3175 925);
DISPLAY INVISIBLE (-3175 925);
FORCEPROP 1 LAST BODY_TYPE PLUMBING
J 2
(-2850 1000);
DISPLAY 1.595745 (-2850 1000);
PAINT GREEN (-2850 1000);
DISPLAY INVISIBLE (-2850 1000);
FORCEPROP 2 LAST CDS_LIB mstr_standard
J 0
(-2850 1050);
PAINT MONO (-2850 1050);
DISPLAY INVISIBLE (-2850 1050);
FORCEPROP 1 LAST PATH I93
J 2
(-2848 1050);
DISPLAY 0.872340 (-2848 1050);
PAINT GREEN (-2848 1050);
DISPLAY INVISIBLE (-2848 1050);
FORCEADD TAP..6
R 2
(-2850 1200);
FORCEPROP 3 LASTPIN (-2900 1200) SIG_NAME M_C_CS_N<4>
J 0
(-2890 1210);
DISPLAY 0.659574 (-2890 1210);
PAINT MONO (-2890 1210);
DISPLAY INVISIBLE (-2890 1210);
FORCEPROP 1 LASTPIN (-2900 1200) BN 4
J 2
(-2848 1208);
DISPLAY 0.617021 (-2848 1208);
PAINT PINK (-2848 1208);
FORCEPROP 1 LAST HDL_TAP TRUE
J 2
(-3175 1075);
DISPLAY 1.595745 (-3175 1075);
PAINT GREEN (-3175 1075);
DISPLAY INVISIBLE (-3175 1075);
FORCEPROP 1 LAST BODY_TYPE PLUMBING
J 2
(-2850 1150);
DISPLAY 1.595745 (-2850 1150);
PAINT GREEN (-2850 1150);
DISPLAY INVISIBLE (-2850 1150);
FORCEPROP 2 LAST CDS_LIB mstr_standard
J 0
(-2850 1200);
PAINT MONO (-2850 1200);
DISPLAY INVISIBLE (-2850 1200);
FORCEPROP 1 LAST PATH I94
J 2
(-2848 1200);
DISPLAY 0.872340 (-2848 1200);
PAINT GREEN (-2848 1200);
DISPLAY INVISIBLE (-2848 1200);
FORCEADD TAP..6
R 2
(-2850 1150);
FORCEPROP 3 LASTPIN (-2900 1150) SIG_NAME M_C_CS_N<3>
J 0
(-2890 1160);
DISPLAY 0.659574 (-2890 1160);
PAINT MONO (-2890 1160);
DISPLAY INVISIBLE (-2890 1160);
FORCEPROP 1 LASTPIN (-2900 1150) BN 3
J 2
(-2848 1158);
DISPLAY 0.617021 (-2848 1158);
PAINT PINK (-2848 1158);
FORCEPROP 1 LAST HDL_TAP TRUE
J 2
(-3175 1025);
DISPLAY 1.595745 (-3175 1025);
PAINT GREEN (-3175 1025);
DISPLAY INVISIBLE (-3175 1025);
FORCEPROP 1 LAST BODY_TYPE PLUMBING
J 2
(-2850 1100);
DISPLAY 1.595745 (-2850 1100);
PAINT GREEN (-2850 1100);
DISPLAY INVISIBLE (-2850 1100);
FORCEPROP 2 LAST CDS_LIB mstr_standard
J 0
(-2850 1150);
PAINT MONO (-2850 1150);
DISPLAY INVISIBLE (-2850 1150);
FORCEPROP 1 LAST PATH I95
J 2
(-2848 1150);
DISPLAY 0.872340 (-2848 1150);
PAINT GREEN (-2848 1150);
DISPLAY INVISIBLE (-2848 1150);
FORCEADD TAP..6
R 2
(-2850 1250);
FORCEPROP 3 LASTPIN (-2900 1250) SIG_NAME M_C_CS_N<5>
J 0
(-2890 1260);
DISPLAY 0.659574 (-2890 1260);
PAINT MONO (-2890 1260);
DISPLAY INVISIBLE (-2890 1260);
FORCEPROP 1 LASTPIN (-2900 1250) BN 5
J 2
(-2848 1258);
DISPLAY 0.617021 (-2848 1258);
PAINT PINK (-2848 1258);
FORCEPROP 1 LAST HDL_TAP TRUE
J 2
(-3175 1125);
DISPLAY 1.595745 (-3175 1125);
PAINT GREEN (-3175 1125);
DISPLAY INVISIBLE (-3175 1125);
FORCEPROP 1 LAST BODY_TYPE PLUMBING
J 2
(-2850 1200);
DISPLAY 1.595745 (-2850 1200);
PAINT GREEN (-2850 1200);
DISPLAY INVISIBLE (-2850 1200);
FORCEPROP 2 LAST CDS_LIB mstr_standard
J 0
(-2850 1250);
PAINT MONO (-2850 1250);
DISPLAY INVISIBLE (-2850 1250);
FORCEPROP 1 LAST PATH I96
J 2
(-2848 1250);
DISPLAY 0.872340 (-2848 1250);
PAINT GREEN (-2848 1250);
DISPLAY INVISIBLE (-2848 1250);
FORCEADD TAP..6
R 2
(-2850 1300);
FORCEPROP 3 LASTPIN (-2900 1300) SIG_NAME M_C_CS_N<6>
J 0
(-2890 1310);
DISPLAY 0.659574 (-2890 1310);
PAINT MONO (-2890 1310);
DISPLAY INVISIBLE (-2890 1310);
FORCEPROP 1 LASTPIN (-2900 1300) BN 6
J 2
(-2848 1308);
DISPLAY 0.617021 (-2848 1308);
PAINT PINK (-2848 1308);
FORCEPROP 1 LAST HDL_TAP TRUE
J 2
(-3175 1175);
DISPLAY 1.595745 (-3175 1175);
PAINT GREEN (-3175 1175);
DISPLAY INVISIBLE (-3175 1175);
FORCEPROP 1 LAST BODY_TYPE PLUMBING
J 2
(-2850 1250);
DISPLAY 1.595745 (-2850 1250);
PAINT GREEN (-2850 1250);
DISPLAY INVISIBLE (-2850 1250);
FORCEPROP 2 LAST CDS_LIB mstr_standard
J 0
(-2850 1300);
PAINT MONO (-2850 1300);
DISPLAY INVISIBLE (-2850 1300);
FORCEPROP 1 LAST PATH I97
J 2
(-2848 1300);
DISPLAY 0.872340 (-2848 1300);
PAINT GREEN (-2848 1300);
DISPLAY INVISIBLE (-2848 1300);
FORCEADD TAP..6
R 2
(-2850 1350);
FORCEPROP 3 LASTPIN (-2900 1350) SIG_NAME M_C_CS_N<7>
J 0
(-2890 1360);
DISPLAY 0.659574 (-2890 1360);
PAINT MONO (-2890 1360);
DISPLAY INVISIBLE (-2890 1360);
FORCEPROP 1 LASTPIN (-2900 1350) BN 7
J 2
(-2848 1358);
DISPLAY 0.617021 (-2848 1358);
PAINT PINK (-2848 1358);
FORCEPROP 1 LAST HDL_TAP TRUE
J 2
(-3175 1225);
DISPLAY 1.595745 (-3175 1225);
PAINT GREEN (-3175 1225);
DISPLAY INVISIBLE (-3175 1225);
FORCEPROP 1 LAST BODY_TYPE PLUMBING
J 2
(-2850 1300);
DISPLAY 1.595745 (-2850 1300);
PAINT GREEN (-2850 1300);
DISPLAY INVISIBLE (-2850 1300);
FORCEPROP 2 LAST CDS_LIB mstr_standard
J 0
(-2850 1350);
PAINT MONO (-2850 1350);
DISPLAY INVISIBLE (-2850 1350);
FORCEPROP 1 LAST PATH I98
J 2
(-2848 1350);
DISPLAY 0.872340 (-2848 1350);
PAINT GREEN (-2848 1350);
DISPLAY INVISIBLE (-2848 1350);
FORCEADD TAP..6
R 2
(-2850 1450);
FORCEPROP 3 LASTPIN (-2900 1450) SIG_NAME M_C_ODT<0>
J 0
(-2890 1460);
DISPLAY 0.659574 (-2890 1460);
PAINT MONO (-2890 1460);
DISPLAY INVISIBLE (-2890 1460);
FORCEPROP 1 LASTPIN (-2900 1450) BN 0
J 2
(-2848 1458);
DISPLAY 0.617021 (-2848 1458);
PAINT PINK (-2848 1458);
FORCEPROP 1 LAST HDL_TAP TRUE
J 2
(-3175 1325);
DISPLAY 1.595745 (-3175 1325);
PAINT GREEN (-3175 1325);
DISPLAY INVISIBLE (-3175 1325);
FORCEPROP 1 LAST BODY_TYPE PLUMBING
J 2
(-2850 1400);
DISPLAY 1.595745 (-2850 1400);
PAINT GREEN (-2850 1400);
DISPLAY INVISIBLE (-2850 1400);
FORCEPROP 2 LAST CDS_LIB mstr_standard
J 0
(-2850 1450);
PAINT MONO (-2850 1450);
DISPLAY INVISIBLE (-2850 1450);
FORCEPROP 1 LAST PATH I99
J 2
(-2848 1450);
DISPLAY 0.872340 (-2848 1450);
PAINT GREEN (-2848 1450);
DISPLAY INVISIBLE (-2848 1450);
FORCEADD PRELIM..10
(-4215 2590);
PAINT GRAY (-4215 2590);
FORCEPROP 1 LAST COMMENT_BODY TRUE
J 0
(-4215 2590);
PAINT ORANGE (-4215 2590);
DISPLAY INVISIBLE (-4215 2590);
FORCEPROP 2 LAST CDS_LIB mstr_misc
J 0
(-4215 2590);
PAINT ORANGE (-4215 2590);
DISPLAY INVISIBLE (-4215 2590);
FORCEADD INTEL_CORP_BPAGE..1
(0 0);
FORCEPROP 1 LAST CDS_CON_LAST_MODIFIED Fri Jun 16 17:48:10 2017
J 0
(-1425 325);
DISPLAY 1.340426 (-1425 325);
PAINT GREEN (-1425 325);
DISPLAY INVISIBLE (-1425 325);
FORCEPROP 1 LAST CUSTOM_TXT_CDS <CURRENT_DESIGN_SHEET> OF <TOTAL_DESIGN_SHEETS>
J 0
(-500 25);
PAINT ORANGE (-500 25);
FORCEPROP 1 LAST CUSTOM_TXT_CDS <CON_LAST_MODIFIED>
J 0
(-4000 100);
PAINT ORANGE (-4000 100);
FORCEPROP 2 LAST CUSTOM_TXT_CDS <XR_PAGE_TITLE>
J 0
(-7890 5250);
DISPLAY 0.638298 (-7890 5250);
PAINT PINK (-7890 5250);
DISPLAY INVISIBLE (-7890 5250);
FORCEPROP 1 LAST SCH_TITLE SKYLAKE - SKT0 - 5 OF 21
J 0
(-7950 50);
DISPLAY 1.212766 (-7950 50);
PAINT GREEN (-7950 50);
FORCEPROP 1 LAST COMMENT_BODY TRUE
J 0
(12 12);
DISPLAY 0.638298 (12 12);
PAINT GREEN (12 12);
DISPLAY INVISIBLE (12 12);
FORCEPROP 2 LAST CDS_LIB mstr_symbols
J 0
(0 0);
PAINT ORANGE (0 0);
DISPLAY INVISIBLE (0 0);
FORCEPROP 2 LAST PAGE_BORDER TRUE
J 0
(-7890 5250);
DISPLAY 0.851064 (-7890 5250);
PAINT PINK (-7890 5250);
DISPLAY INVISIBLE (-7890 5250);
FORCEPROP 2 LAST CDS_XR_PAGE_TITLE CR-25 : @BASEBOARD_FAB2_LIB.BASEBOARD_FAB2(SCH_1):PAGE25
J 0
(-7890 5250);
DISPLAY 0.638298 (-7890 5250);
PAINT PINK (-7890 5250);
DISPLAY INVISIBLE (-7890 5250);
FORCEADD DESIGN_NOTE..1
(-6400 425);
FORCEPROP 0 LAST L1 CPU SYMBOLS 1-30 ARE PRELIMINARY AND SUBJECT TO CHANGE
J 0
(-6600 300);
DISPLAY 1.021277 (-6600 300);
PAINT ORANGE (-6600 300);
FORCEPROP 1 LAST COMMENT_BODY TRUE
J 0
(-6375 525);
DISPLAY 0.978723 (-6375 525);
PAINT ORANGE (-6375 525);
DISPLAY INVISIBLE (-6375 525);
FORCEPROP 2 LAST CDS_LIB mstr_symbols
J 0
(-6400 425);
PAINT ORANGE (-6400 425);
DISPLAY INVISIBLE (-6400 425);
WIRE 17 -1 (-2050 4775)(-2800 4775);
FORCEPROP 2 LAST SIG_NAME M_C_DQS_DP<17:0>
J 0
(-2700 4785);
DISPLAY 0.617021 (-2700 4785);
PAINT ORANGE (-2700 4785);
WIRE 17 -1 (-2800 4725)(-2800 4775);
WIRE 17 -1 (-2800 4675)(-2800 4725);
WIRE 17 -1 (-2800 4625)(-2800 4675);
WIRE 17 -1 (-2800 4575)(-2800 4625);
WIRE 17 -1 (-2800 4525)(-2800 4575);
WIRE 17 -1 (-2800 4475)(-2800 4525);
WIRE 17 -1 (-2800 4425)(-2800 4475);
WIRE 17 -1 (-2800 4375)(-2800 4425);
WIRE 17 -1 (-2800 3875)(-2800 3925);
WIRE 17 -1 (-2800 3925)(-2800 3975);
WIRE 17 -1 (-2800 4325)(-2800 4375);
WIRE 17 -1 (-2800 4275)(-2800 4325);
WIRE 17 -1 (-2800 3975)(-2800 4025);
WIRE 17 -1 (-2800 4025)(-2800 4075);
WIRE 17 -1 (-2800 4225)(-2800 4275);
WIRE 17 -1 (-2800 4175)(-2800 4225);
WIRE 17 -1 (-2800 4075)(-2800 4125);
WIRE 17 -1 (-2800 4125)(-2800 4175);
WIRE 17 -1 (-2050 2850)(-2800 2850);
FORCEPROP 2 LAST SIG_NAME M_C_MA<17:0>
J 0
(-2700 2860);
DISPLAY 0.617021 (-2700 2860);
PAINT ORANGE (-2700 2860);
WIRE 17 -1 (-2800 2825)(-2800 2850);
WIRE 17 -1 (-2800 2775)(-2800 2825);
WIRE 17 -1 (-2800 2725)(-2800 2775);
WIRE 17 -1 (-2800 2675)(-2800 2725);
WIRE 17 -1 (-2800 2625)(-2800 2675);
WIRE 17 -1 (-2800 2575)(-2800 2625);
WIRE 17 -1 (-2800 2525)(-2800 2575);
WIRE 17 -1 (-2800 2475)(-2800 2525);
WIRE 17 -1 (-2800 2425)(-2800 2475);
WIRE 17 -1 (-2800 2375)(-2800 2425);
WIRE 17 -1 (-2800 2325)(-2800 2375);
WIRE 17 -1 (-2800 2275)(-2800 2325);
WIRE 17 -1 (-2800 2225)(-2800 2275);
WIRE 17 -1 (-2800 1975)(-2800 2025);
WIRE 17 -1 (-2800 2175)(-2800 2225);
WIRE 17 -1 (-2800 2125)(-2800 2175);
WIRE 17 -1 (-2800 2025)(-2800 2075);
WIRE 17 -1 (-2800 2075)(-2800 2125);
WIRE 17 -1 (-2050 3800)(-2800 3800);
FORCEPROP 2 LAST SIG_NAME M_C_DQS_DN<17:0>
J 0
(-2700 3810);
DISPLAY 0.617021 (-2700 3810);
PAINT ORANGE (-2700 3810);
WIRE 17 -1 (-2800 3775)(-2800 3800);
WIRE 17 -1 (-2800 3725)(-2800 3775);
WIRE 17 -1 (-2800 3675)(-2800 3725);
WIRE 17 -1 (-2800 3625)(-2800 3675);
WIRE 17 -1 (-2800 3575)(-2800 3625);
WIRE 17 -1 (-2800 3525)(-2800 3575);
WIRE 17 -1 (-2800 3475)(-2800 3525);
WIRE 17 -1 (-2800 3425)(-2800 3475);
WIRE 17 -1 (-2800 3375)(-2800 3425);
WIRE 17 -1 (-2800 3325)(-2800 3375);
WIRE 17 -1 (-2800 3275)(-2800 3325);
WIRE 17 -1 (-2800 3225)(-2800 3275);
WIRE 17 -1 (-2800 3175)(-2800 3225);
WIRE 17 -1 (-2800 3125)(-2800 3175);
WIRE 17 -1 (-2800 3075)(-2800 3125);
WIRE 17 -1 (-2800 3025)(-2800 3075);
WIRE 17 -1 (-2800 2975)(-2800 3025);
WIRE 17 -1 (-2800 2925)(-2800 2975);
WIRE 17 -1 (-2050 1650)(-2800 1650);
FORCEPROP 2 LAST SIG_NAME M_C_ODT<3:0>
J 0
(-2700 1660);
DISPLAY 0.617021 (-2700 1660);
PAINT ORANGE (-2700 1660);
WIRE 17 -1 (-2800 1625)(-2800 1650);
WIRE 17 -1 (-2800 1575)(-2800 1625);
WIRE 17 -1 (-2800 1525)(-2800 1575);
WIRE 17 -1 (-2800 1475)(-2800 1525);
WIRE 17 -1 (-2050 1400)(-2800 1400);
FORCEPROP 2 LAST SIG_NAME M_C_CS_N<7:0>
J 0
(-2700 1410);
DISPLAY 0.617021 (-2700 1410);
PAINT ORANGE (-2700 1410);
WIRE 17 -1 (-2800 1375)(-2800 1400);
WIRE 17 -1 (-2800 1325)(-2800 1375);
WIRE 17 -1 (-2800 1275)(-2800 1325);
WIRE 17 -1 (-2800 1225)(-2800 1275);
WIRE 17 -1 (-2800 1175)(-2800 1225);
WIRE 17 -1 (-2800 1125)(-2800 1175);
WIRE 17 -1 (-2800 1075)(-2800 1125);
WIRE 17 -1 (-2800 1025)(-2800 1075);
WIRE 17 -1 (-2050 1900)(-2800 1900);
FORCEPROP 2 LAST SIG_NAME M_C_CKE<3:0>
J 0
(-2700 1910);
DISPLAY 0.617021 (-2700 1910);
PAINT ORANGE (-2700 1910);
WIRE 17 -1 (-2800 1875)(-2800 1900);
WIRE 17 -1 (-2800 1825)(-2800 1875);
WIRE 17 -1 (-2800 1775)(-2800 1825);
WIRE 17 -1 (-2800 1725)(-2800 1775);
WIRE 17 -1 (-2050 950)(-2800 950);
FORCEPROP 2 LAST SIG_NAME M_C_BG<1:0>
J 0
(-2700 960);
DISPLAY 0.617021 (-2700 960);
PAINT ORANGE (-2700 960);
WIRE 17 -1 (-2800 925)(-2800 950);
WIRE 17 -1 (-2800 875)(-2800 925);
WIRE 17 -1 (-2050 850)(-2800 850);
FORCEPROP 2 LAST SIG_NAME M_C_BA<1:0>
J 0
(-2700 860);
DISPLAY 0.617021 (-2700 860);
PAINT ORANGE (-2700 860);
WIRE 17 -1 (-2800 825)(-2800 850);
WIRE 17 -1 (-2800 775)(-2800 825);
WIRE 17 -1 (-5625 1575)(-5625 1625);
WIRE 17 -1 (-5625 1625)(-5625 1675);
WIRE 17 -1 (-5625 1675)(-5625 1725);
WIRE 17 -1 (-5625 1725)(-5625 1775);
WIRE 17 -1 (-5625 1775)(-5625 1825);
WIRE 17 -1 (-5625 1825)(-5625 1875);
WIRE 17 -1 (-5625 1875)(-5625 1925);
WIRE 17 -1 (-5625 1925)(-5625 1975);
WIRE 17 -1 (-5625 1975)(-5625 2025);
WIRE 17 -1 (-5625 2025)(-5625 2075);
WIRE 17 -1 (-5625 2075)(-5625 2125);
WIRE 17 -1 (-5625 2125)(-5625 2175);
WIRE 17 -1 (-5625 2175)(-5625 2225);
WIRE 17 -1 (-5625 2225)(-5625 2275);
WIRE 17 -1 (-5625 2275)(-5625 2325);
WIRE 17 -1 (-5625 2325)(-5625 2375);
WIRE 17 -1 (-5625 2375)(-5625 2425);
WIRE 17 -1 (-5625 2425)(-5625 2475);
WIRE 17 -1 (-5625 2475)(-5625 2525);
WIRE 17 -1 (-5625 2525)(-5625 2575);
WIRE 17 -1 (-5625 2575)(-5625 2625);
WIRE 17 -1 (-5625 2625)(-5625 2675);
WIRE 17 -1 (-5625 2675)(-5625 2725);
WIRE 17 -1 (-5625 2725)(-5625 2775);
WIRE 17 -1 (-5625 2775)(-5625 2825);
WIRE 17 -1 (-5625 2825)(-5625 2875);
WIRE 17 -1 (-5625 2875)(-5625 2925);
WIRE 17 -1 (-5625 2925)(-5625 2975);
WIRE 17 -1 (-5625 2975)(-5625 3025);
WIRE 17 -1 (-5625 3025)(-5625 3075);
WIRE 17 -1 (-5625 3075)(-5625 3125);
WIRE 17 -1 (-5625 3125)(-5625 3175);
WIRE 17 -1 (-5625 3175)(-5625 3225);
WIRE 17 -1 (-5625 3225)(-5625 3275);
WIRE 17 -1 (-5625 3275)(-5625 3325);
WIRE 17 -1 (-5625 3325)(-5625 3375);
WIRE 17 -1 (-5625 3375)(-5625 3425);
WIRE 17 -1 (-5625 3425)(-5625 3475);
WIRE 17 -1 (-5625 4825)(-6375 4825);
FORCEPROP 2 LAST SIG_NAME M_C_DQ<63:0>
J 0
(-6325 4835);
DISPLAY 0.617021 (-6325 4835);
PAINT ORANGE (-6325 4835);
WIRE 17 -1 (-5625 3475)(-5625 3525);
WIRE 17 -1 (-5625 3525)(-5625 3575);
WIRE 17 -1 (-5625 4725)(-5625 4825);
WIRE 17 -1 (-5625 4675)(-5625 4725);
WIRE 17 -1 (-5625 3575)(-5625 3625);
WIRE 17 -1 (-5625 3625)(-5625 3675);
WIRE 17 -1 (-5625 4625)(-5625 4675);
WIRE 17 -1 (-5625 4575)(-5625 4625);
WIRE 17 -1 (-5625 3675)(-5625 3725);
WIRE 17 -1 (-5625 3725)(-5625 3775);
WIRE 17 -1 (-5625 4525)(-5625 4575);
WIRE 17 -1 (-5625 4475)(-5625 4525);
WIRE 17 -1 (-5625 3775)(-5625 3825);
WIRE 17 -1 (-5625 3825)(-5625 3875);
WIRE 17 -1 (-5625 4425)(-5625 4475);
WIRE 17 -1 (-5625 4375)(-5625 4425);
WIRE 17 -1 (-5625 3875)(-5625 3925);
WIRE 17 -1 (-5625 3925)(-5625 3975);
WIRE 17 -1 (-5625 4325)(-5625 4375);
WIRE 17 -1 (-5625 4275)(-5625 4325);
WIRE 17 -1 (-5625 3975)(-5625 4025);
WIRE 17 -1 (-5625 4025)(-5625 4075);
WIRE 17 -1 (-5625 4225)(-5625 4275);
WIRE 17 -1 (-5625 4175)(-5625 4225);
WIRE 17 -1 (-5625 4075)(-5625 4125);
WIRE 17 -1 (-5625 4125)(-5625 4175);
WIRE 17 -1 (-5625 1500)(-6375 1500);
FORCEPROP 2 LAST SIG_NAME M_C_ECC<7:0>
J 0
(-6325 1510);
DISPLAY 0.617021 (-6325 1510);
PAINT ORANGE (-6325 1510);
WIRE 17 -1 (-5625 1475)(-5625 1500);
WIRE 17 -1 (-5625 1425)(-5625 1475);
WIRE 17 -1 (-5625 1375)(-5625 1425);
WIRE 17 -1 (-5625 1325)(-5625 1375);
WIRE 17 -1 (-5625 1275)(-5625 1325);
WIRE 17 -1 (-5625 1225)(-5625 1275);
WIRE 17 -1 (-5625 1175)(-5625 1225);
WIRE 17 -1 (-5625 1125)(-5625 1175);
WIRE 17 -1 (-5625 1050)(-6375 1050);
FORCEPROP 2 LAST SIG_NAME M_C_CLK_DP<3:0>
J 0
(-6325 1060);
DISPLAY 0.617021 (-6325 1060);
PAINT ORANGE (-6325 1060);
WIRE 17 -1 (-5625 1025)(-5625 1050);
WIRE 17 -1 (-5625 975)(-5625 1025);
WIRE 17 -1 (-5625 925)(-5625 975);
WIRE 17 -1 (-5625 875)(-5625 925);
WIRE 17 -1 (-5625 850)(-6375 850);
FORCEPROP 2 LAST SIG_NAME M_C_CLK_DN<3:0>
J 0
(-6325 860);
DISPLAY 0.617021 (-6325 860);
PAINT ORANGE (-6325 860);
WIRE 17 -1 (-5625 825)(-5625 850);
WIRE 17 -1 (-5625 775)(-5625 825);
WIRE 17 -1 (-5625 725)(-5625 775);
WIRE 17 -1 (-5625 675)(-5625 725);
WIRE 16 -1 (-3325 3250)(-2900 3250);
WIRE 16 -1 (-5025 4250)(-5525 4250);
WIRE 16 -1 (-5025 3550)(-5525 3550);
WIRE 16 -1 (-3325 3900)(-2900 3900);
WIRE 16 -1 (-5025 4150)(-5525 4150);
WIRE 16 -1 (-3325 1550)(-2900 1550);
WIRE 16 -1 (-5525 3250)(-5025 3250);
WIRE 16 -1 (-5525 3150)(-5025 3150);
WIRE 16 -1 (-5525 1750)(-5025 1750);
WIRE 16 -1 (-5025 550)(-6375 550);
FORCEPROP 2 LAST SIG_NAME M_C_C<2>
J 0
(-6325 560);
DISPLAY 0.617021 (-6325 560);
PAINT ORANGE (-6325 560);
WIRE 16 -1 (-5025 800)(-5525 800);
WIRE 16 -1 (-5025 750)(-5525 750);
WIRE 16 -1 (-5025 700)(-5525 700);
WIRE 16 -1 (-5025 650)(-5525 650);
WIRE 16 -1 (-5025 1000)(-5525 1000);
WIRE 16 -1 (-5025 950)(-5525 950);
WIRE 16 -1 (-5025 900)(-5525 900);
WIRE 16 -1 (-5025 850)(-5525 850);
WIRE 16 -1 (-5525 2000)(-5025 2000);
WIRE 16 -1 (-5525 1950)(-5025 1950);
WIRE 16 -1 (-5525 1900)(-5025 1900);
WIRE 16 -1 (-5025 1850)(-5525 1850);
WIRE 16 -1 (-5525 1800)(-5025 1800);
WIRE 16 -1 (-5025 1700)(-5525 1700);
WIRE 16 -1 (-5525 1650)(-5025 1650);
WIRE 16 -1 (-5525 1600)(-5025 1600);
WIRE 16 -1 (-5525 1550)(-5025 1550);
WIRE 16 -1 (-5025 1450)(-5525 1450);
WIRE 16 -1 (-5025 1400)(-5525 1400);
WIRE 16 -1 (-5025 1350)(-5525 1350);
WIRE 16 -1 (-5025 1300)(-5525 1300);
WIRE 16 -1 (-5025 1250)(-5525 1250);
WIRE 16 -1 (-5025 1200)(-5525 1200);
WIRE 16 -1 (-5025 1150)(-5525 1150);
WIRE 16 -1 (-5025 1100)(-5525 1100);
WIRE 16 -1 (-5025 4050)(-5525 4050);
WIRE 16 -1 (-5025 4000)(-5525 4000);
WIRE 16 -1 (-5025 3950)(-5525 3950);
WIRE 16 -1 (-5025 3900)(-5525 3900);
WIRE 16 -1 (-5025 3850)(-5525 3850);
WIRE 16 -1 (-5025 3800)(-5525 3800);
WIRE 16 -1 (-5025 3750)(-5525 3750);
WIRE 16 -1 (-5025 3700)(-5525 3700);
WIRE 16 -1 (-5525 3650)(-5025 3650);
WIRE 16 -1 (-5525 3600)(-5025 3600);
WIRE 16 -1 (-5525 3500)(-5025 3500);
WIRE 16 -1 (-5525 3450)(-5025 3450);
WIRE 16 -1 (-5025 3400)(-5525 3400);
WIRE 16 -1 (-5525 3350)(-5025 3350);
WIRE 16 -1 (-5525 3300)(-5025 3300);
WIRE 16 -1 (-5525 3200)(-5025 3200);
WIRE 16 -1 (-5525 3100)(-5025 3100);
WIRE 16 -1 (-5025 3050)(-5525 3050);
WIRE 16 -1 (-5525 3000)(-5025 3000);
WIRE 16 -1 (-5525 2950)(-5025 2950);
WIRE 16 -1 (-5525 2900)(-5025 2900);
WIRE 16 -1 (-5525 2850)(-5025 2850);
WIRE 16 -1 (-5525 2800)(-5025 2800);
WIRE 16 -1 (-5525 2750)(-5025 2750);
WIRE 16 -1 (-5025 2700)(-5525 2700);
WIRE 16 -1 (-5525 2650)(-5025 2650);
WIRE 16 -1 (-5525 2550)(-5025 2550);
WIRE 16 -1 (-5525 2500)(-5025 2500);
WIRE 16 -1 (-5025 2450)(-5525 2450);
WIRE 16 -1 (-5525 2400)(-5025 2400);
WIRE 16 -1 (-5525 2350)(-5025 2350);
WIRE 16 -1 (-5025 2300)(-5525 2300);
WIRE 16 -1 (-5525 2250)(-5025 2250);
WIRE 16 -1 (-5525 2200)(-5025 2200);
WIRE 16 -1 (-5525 2150)(-5025 2150);
WIRE 16 -1 (-5525 2100)(-5025 2100);
WIRE 16 -1 (-5525 2050)(-5025 2050);
WIRE 16 -1 (-5525 2600)(-5025 2600);
WIRE 16 -1 (-5025 4700)(-5525 4700);
WIRE 16 -1 (-5025 4650)(-5525 4650);
WIRE 16 -1 (-5025 4600)(-5525 4600);
WIRE 16 -1 (-5025 4550)(-5525 4550);
WIRE 16 -1 (-5025 4500)(-5525 4500);
WIRE 16 -1 (-5025 4450)(-5525 4450);
WIRE 16 -1 (-5025 4400)(-5525 4400);
WIRE 16 -1 (-5025 4350)(-5525 4350);
WIRE 16 -1 (-5025 4300)(-5525 4300);
WIRE 16 -1 (-5025 4200)(-5525 4200);
WIRE 16 -1 (-5025 4100)(-5525 4100);
WIRE 16 -1 (-3325 800)(-2900 800);
WIRE 16 -1 (-3325 750)(-2900 750);
WIRE 16 -1 (-3325 900)(-2900 900);
WIRE 16 -1 (-3325 850)(-2900 850);
WIRE 16 -1 (-3325 1850)(-2900 1850);
WIRE 16 -1 (-3325 1800)(-2900 1800);
WIRE 16 -1 (-3325 1750)(-2900 1750);
WIRE 16 -1 (-3325 1700)(-2900 1700);
WIRE 16 -1 (-3325 1350)(-2900 1350);
WIRE 16 -1 (-3325 1300)(-2900 1300);
WIRE 16 -1 (-3325 1250)(-2900 1250);
WIRE 16 -1 (-3325 1200)(-2900 1200);
WIRE 16 -1 (-3325 1150)(-2900 1150);
WIRE 16 -1 (-3325 1100)(-2900 1100);
WIRE 16 -1 (-3325 1050)(-2900 1050);
WIRE 16 -1 (-3325 1000)(-2900 1000);
WIRE 16 -1 (-3325 2000)(-2900 2000);
WIRE 16 -1 (-3325 1950)(-2900 1950);
WIRE 16 -1 (-3325 1600)(-2900 1600);
WIRE 16 -1 (-3325 1500)(-2900 1500);
WIRE 16 -1 (-3325 1450)(-2900 1450);
WIRE 16 -1 (-3325 550)(-2050 550);
FORCEPROP 2 LAST SIG_NAME M_C_PAR
J 0
(-2725 560);
DISPLAY 0.617021 (-2725 560);
PAINT ORANGE (-2725 560);
WIRE 16 -1 (-3325 650)(-2050 650);
FORCEPROP 2 LAST SIG_NAME M_C_ACT_N
J 0
(-2725 660);
DISPLAY 0.617021 (-2725 660);
PAINT ORANGE (-2725 660);
WIRE 16 -1 (-3325 600)(-2050 600);
FORCEPROP 2 LAST SIG_NAME M_C_ALERT_N
J 0
(-2725 610);
DISPLAY 0.617021 (-2725 610);
PAINT ORANGE (-2725 610);
WIRE 16 -1 (-3325 3750)(-2900 3750);
WIRE 16 -1 (-3325 3700)(-2900 3700);
WIRE 16 -1 (-3325 3650)(-2900 3650);
WIRE 16 -1 (-3325 3600)(-2900 3600);
WIRE 16 -1 (-3325 3550)(-2900 3550);
WIRE 16 -1 (-3325 3500)(-2900 3500);
WIRE 16 -1 (-3325 3450)(-2900 3450);
WIRE 16 -1 (-3325 3400)(-2900 3400);
WIRE 16 -1 (-3325 3350)(-2900 3350);
WIRE 16 -1 (-3325 3300)(-2900 3300);
WIRE 16 -1 (-3325 3200)(-2900 3200);
WIRE 16 -1 (-3325 3150)(-2900 3150);
WIRE 16 -1 (-3325 3100)(-2900 3100);
WIRE 16 -1 (-3325 3050)(-2900 3050);
WIRE 16 -1 (-3325 3000)(-2900 3000);
WIRE 16 -1 (-3325 2950)(-2900 2950);
WIRE 16 -1 (-3325 2900)(-2900 2900);
WIRE 16 -1 (-3325 4050)(-2900 4050);
WIRE 16 -1 (-3325 4000)(-2900 4000);
WIRE 16 -1 (-3325 3950)(-2900 3950);
WIRE 16 -1 (-3325 3850)(-2900 3850);
WIRE 16 -1 (-3325 2800)(-2900 2800);
WIRE 16 -1 (-3325 2750)(-2900 2750);
WIRE 16 -1 (-3325 2700)(-2900 2700);
WIRE 16 -1 (-3325 2650)(-2900 2650);
WIRE 16 -1 (-3325 2600)(-2900 2600);
WIRE 16 -1 (-3325 2550)(-2900 2550);
WIRE 16 -1 (-3325 2500)(-2900 2500);
WIRE 16 -1 (-3325 2450)(-2900 2450);
WIRE 16 -1 (-3325 2400)(-2900 2400);
WIRE 16 -1 (-3325 2350)(-2900 2350);
WIRE 16 -1 (-3325 2300)(-2900 2300);
WIRE 16 -1 (-3325 2250)(-2900 2250);
WIRE 16 -1 (-3325 2200)(-2900 2200);
WIRE 16 -1 (-3325 2150)(-2900 2150);
WIRE 16 -1 (-3325 2100)(-2900 2100);
WIRE 16 -1 (-3325 2050)(-2900 2050);
WIRE 16 -1 (-3325 4700)(-2900 4700);
WIRE 16 -1 (-3325 4650)(-2900 4650);
WIRE 16 -1 (-3325 4600)(-2900 4600);
WIRE 16 -1 (-3325 4550)(-2900 4550);
WIRE 16 -1 (-3325 4500)(-2900 4500);
WIRE 16 -1 (-3325 4450)(-2900 4450);
WIRE 16 -1 (-3325 4400)(-2900 4400);
WIRE 16 -1 (-3325 4350)(-2900 4350);
WIRE 16 -1 (-3325 4300)(-2900 4300);
WIRE 16 -1 (-3325 4250)(-2900 4250);
WIRE 16 -1 (-3325 4200)(-2900 4200);
WIRE 16 -1 (-3325 4150)(-2900 4150);
WIRE 16 -1 (-3325 4100)(-2900 4100);
FORCENOTE
SKYLAKE - SKT0 - 5 OF 21
(-1625 150) 0;
DISPLAY LEFT (-1625 150);
DISPLAY 1.021277 (-1625 150);
PAINT RED (-1625 150);
FORCENOTE
ROOM=CPU0
(-7950 375) 0;
DISPLAY LEFT (-7950 375);
DISPLAY 1.382979 (-7950 375);
PAINT PURPLE (-7950 375);
FORCENOTE
BOM_COST=PROC_SOCKET
(-7950 250) 0;
DISPLAY LEFT (-7950 250);
DISPLAY 1.382979 (-7950 250);
PAINT PURPLE (-7950 250);
QUIT
